FILE_TYPE = MACRO_DRAWING;
SET COLOR_WIRE YELLOW;
SET COLOR_PROP ORANGE;
SET COLOR_DOT WHITE;
SET COLOR_ARC YELLOW;
SET COLOR_BODY GREEN;
SET COLOR_NOTE PURPLE;
SET PROP_DISPLAY VALUE;
SET PAGE_NUMBER P15;
SET PATH_NUMBER P406;
FORCEADD UNIVERSAL_POWER..1
(1850 -700);
FORCEPROP 3 LASTPIN (1850 -750) SIG_NAME P1V8_AUX\g
J 0
(1860 -740);
DISPLAY 0.659574 (1860 -740);
PAINT MONO (1860 -740);
DISPLAY INVISIBLE (1860 -740);
FORCEPROP 1 LAST HDL_POWER P1V8_AUX
J 1
(1850 -650);
DISPLAY 0.702128 (1850 -650);
PAINT GREEN (1850 -650);
FORCEPROP 1 LAST PATH I1
J 0
(1900 -675);
DISPLAY 0.872340 (1900 -675);
PAINT AQUA (1900 -675);
DISPLAY INVISIBLE (1900 -675);
FORCEPROP 2 LAST CDS_LIB logical_power
J 0
(1850 -700);
DISPLAY INVISIBLE (1850 -700);
FORCEADD OFFPAGE..3
(3925 2325);
FORCEPROP 2 LAST $XR1 15 
J 0
(4229 2325);
DISPLAY 0.638298 (4229 2325);
PAINT MONO (4229 2325);
FORCEPROP 2 LAST $XR0 10 
J 0
(4139 2325);
DISPLAY 0.638298 (4139 2325);
PAINT MONO (4139 2325);
FORCEPROP 2 LAST PATH I101
J 0
(4200 2375);
DISPLAY 1.021277 (4200 2375);
DISPLAY INVISIBLE (4200 2375);
FORCEPROP 1 LAST COMMENT_BODY TRUE
J 0
(3875 2225);
DISPLAY 0.872340 (3875 2225);
PAINT PEACH (3875 2225);
DISPLAY INVISIBLE (3875 2225);
FORCEPROP 1 LAST OFFPAGE TRUE
J 0
(4250 2200);
DISPLAY 0.872340 (4250 2200);
PAINT GREEN (4250 2200);
DISPLAY INVISIBLE (4250 2200);
FORCEPROP 2 LAST CDS_LIB standard
J 0
(3925 2325);
DISPLAY INVISIBLE (3925 2325);
FORCEADD OFFPAGE..3
(4500 2825);
FORCEPROP 2 LAST $XR0 10 
J 0
(4714 2825);
DISPLAY 0.638298 (4714 2825);
PAINT MONO (4714 2825);
FORCEPROP 2 LAST PATH I102
J 0
(4725 2875);
DISPLAY 1.021277 (4725 2875);
DISPLAY INVISIBLE (4725 2875);
FORCEPROP 1 LAST COMMENT_BODY TRUE
J 0
(4450 2725);
DISPLAY 0.872340 (4450 2725);
PAINT PEACH (4450 2725);
DISPLAY INVISIBLE (4450 2725);
FORCEPROP 1 LAST OFFPAGE TRUE
J 0
(4825 2700);
DISPLAY 0.872340 (4825 2700);
PAINT GREEN (4825 2700);
DISPLAY INVISIBLE (4825 2700);
FORCEPROP 2 LAST CDS_LIB standard
J 0
(4500 2825);
DISPLAY INVISIBLE (4500 2825);
FORCEADD OFFPAGE..3
(4500 2775);
FORCEPROP 2 LAST $XR0 10 
J 0
(4714 2775);
DISPLAY 0.638298 (4714 2775);
PAINT MONO (4714 2775);
FORCEPROP 2 LAST PATH I103
J 0
(4725 2825);
DISPLAY 1.021277 (4725 2825);
DISPLAY INVISIBLE (4725 2825);
FORCEPROP 1 LAST COMMENT_BODY TRUE
J 0
(4450 2675);
DISPLAY 0.872340 (4450 2675);
PAINT PEACH (4450 2675);
DISPLAY INVISIBLE (4450 2675);
FORCEPROP 1 LAST OFFPAGE TRUE
J 0
(4825 2650);
DISPLAY 0.872340 (4825 2650);
PAINT GREEN (4825 2650);
DISPLAY INVISIBLE (4825 2650);
FORCEPROP 2 LAST CDS_LIB standard
J 0
(4500 2775);
DISPLAY INVISIBLE (4500 2775);
FORCEADD Q_CAP..1
(4450 2375);
FORCEPROP 1 LAST VALUE 22UF
J 0
(4500 2425);
DISPLAY 0.510638 (4500 2425);
PAINT SKYBLUE (4500 2425);
FORCEPROP 1 LAST TOLERANCE 20%
J 0
(4500 2325);
DISPLAY 0.510638 (4500 2325);
PAINT SKYBLUE (4500 2325);
FORCEPROP 1 LAST MATERIAL X6S
J 0
(4500 2275);
DISPLAY 0.510638 (4500 2275);
PAINT SKYBLUE (4500 2275);
FORCEPROP 1 LAST VOLTAGE 6.3V
J 0
(4500 2375);
DISPLAY 0.510638 (4500 2375);
PAINT SKYBLUE (4500 2375);
FORCEPROP 1 LAST PACK_TYPE C0603
J 0
(4500 2225);
DISPLAY 0.510638 (4500 2225);
PAINT SKYBLUE (4500 2225);
FORCEPROP 1 LAST PART_NUMBER CH6221ME900
R 3
J 0
(4375 2500);
DISPLAY 0.510638 (4375 2500);
PAINT WHITE (4375 2500);
FORCEPROP 1 LAST PATH I117
J 0
(4500 2525);
DISPLAY 0.978723 (4500 2525);
PAINT WHITE (4500 2525);
DISPLAY INVISIBLE (4500 2525);
FORCEPROP 2 LAST CDS_LIB pure_quanta
J 0
(4450 2375);
DISPLAY INVISIBLE (4450 2375);
FORCEPROP 1 LAST LOCATION C42
J 0
(4500 2475);
DISPLAY 0.702128 (4500 2475);
PAINT YELLOW (4500 2475);
FORCEPROP 1 LASTPIN (4450 2475) $PN 1
J 0
(4460 2455);
DISPLAY 0.808511 (4460 2455);
PAINT WHITE (4460 2455);
FORCEPROP 1 LASTPIN (4450 2275) $PN 2
J 0
(4460 2255);
DISPLAY 0.808511 (4460 2255);
PAINT WHITE (4460 2255);
FORCEPROP 0 LAST $SEC 1
J 0
(4500 2525);
DISPLAY 0.680851 (4500 2525);
PAINT MONO (4500 2525);
DISPLAY INVISIBLE (4500 2525);
FORCEPROP 0 LAST CDS_SEC 1
J 0
(4500 2525);
DISPLAY 0.680851 (4500 2525);
DISPLAY INVISIBLE (4500 2525);
FORCEADD UNIVERSAL_GND..1
(4625 2100);
FORCEPROP 3 LASTPIN (4625 2150) SIG_NAME GND\g
J 0
(4635 2160);
DISPLAY 0.659574 (4635 2160);
PAINT MONO (4635 2160);
DISPLAY INVISIBLE (4635 2160);
FORCEPROP 1 LAST HDL_POWER GND
J 1
(4650 2025);
DISPLAY 0.702128 (4650 2025);
PAINT GREEN (4650 2025);
DISPLAY INVISIBLE (4650 2025);
FORCEPROP 1 LAST PATH I118
J 0
(4700 2100);
DISPLAY 0.872340 (4700 2100);
PAINT AQUA (4700 2100);
DISPLAY INVISIBLE (4700 2100);
FORCEPROP 2 LAST CDS_LIB logical_power
J 0
(4625 2100);
DISPLAY INVISIBLE (4625 2100);
FORCEADD Q_CAP..1
(4675 2375);
FORCEPROP 1 LAST MATERIAL X6S
J 0
(4725 2275);
DISPLAY 0.510638 (4725 2275);
PAINT SKYBLUE (4725 2275);
FORCEPROP 1 LAST TOLERANCE 10%
J 0
(4725 2325);
DISPLAY 0.510638 (4725 2325);
PAINT SKYBLUE (4725 2325);
FORCEPROP 1 LAST PACK_TYPE C0402
J 0
(4725 2175);
DISPLAY 0.510638 (4725 2175);
PAINT SKYBLUE (4725 2175);
FORCEPROP 1 LAST PART_NUMBER CH5104KEB02
J 0
(4725 2225);
DISPLAY 0.510638 (4725 2225);
PAINT WHITE (4725 2225);
FORCEPROP 1 LAST VOLTAGE 25V
J 0
(4725 2375);
DISPLAY 0.510638 (4725 2375);
PAINT SKYBLUE (4725 2375);
FORCEPROP 1 LAST VALUE 1UF
J 0
(4725 2425);
DISPLAY 0.510638 (4725 2425);
PAINT SKYBLUE (4725 2425);
FORCEPROP 1 LAST PATH I119
J 0
(4725 2525);
DISPLAY 0.978723 (4725 2525);
PAINT WHITE (4725 2525);
DISPLAY INVISIBLE (4725 2525);
FORCEPROP 2 LAST CDS_LIB pure_quanta
J 0
(4675 2375);
DISPLAY INVISIBLE (4675 2375);
FORCEPROP 1 LAST LOCATION C43
J 0
(4725 2475);
DISPLAY 0.702128 (4725 2475);
PAINT YELLOW (4725 2475);
FORCEPROP 1 LASTPIN (4675 2475) $PN 1
J 0
(4685 2455);
DISPLAY 0.808511 (4685 2455);
PAINT WHITE (4685 2455);
FORCEPROP 1 LASTPIN (4675 2275) $PN 2
J 0
(4685 2255);
DISPLAY 0.808511 (4685 2255);
PAINT WHITE (4685 2255);
FORCEPROP 2 LAST $SEC 1
J 0
(4725 2575);
DISPLAY 0.680851 (4725 2575);
PAINT MONO (4725 2575);
DISPLAY INVISIBLE (4725 2575);
FORCEPROP 0 LAST CDS_SEC 1
J 0
(4725 2575);
DISPLAY 0.680851 (4725 2575);
PAINT MONO (4725 2575);
DISPLAY INVISIBLE (4725 2575);
FORCEADD OFFPAGE..4
(4875 2575);
FORCEPROP 2 LAST $XR0 10 
J 0
(5061 2575);
DISPLAY 0.638298 (5061 2575);
PAINT MONO (5061 2575);
FORCEPROP 2 LAST PATH I120
J 0
(5075 2625);
DISPLAY 1.021277 (5075 2625);
DISPLAY INVISIBLE (5075 2625);
FORCEPROP 1 LAST COMMENT_BODY TRUE
J 0
(4850 2475);
DISPLAY 0.872340 (4850 2475);
PAINT PEACH (4850 2475);
DISPLAY INVISIBLE (4850 2475);
FORCEPROP 1 LAST OFFPAGE TRUE
J 0
(5200 2450);
DISPLAY 0.872340 (5200 2450);
PAINT GREEN (5200 2450);
DISPLAY INVISIBLE (5200 2450);
FORCEPROP 2 LAST CDS_LIB standard
J 0
(4875 2575);
DISPLAY INVISIBLE (4875 2575);
FORCEADD OFFPAGE..4
(5200 3375);
FORCEPROP 2 LAST $XR0 50 
J 0
(5386 3375);
DISPLAY 0.638298 (5386 3375);
PAINT MONO (5386 3375);
FORCEPROP 2 LAST PATH I125
J 0
(5375 3450);
DISPLAY 1.021277 (5375 3450);
DISPLAY INVISIBLE (5375 3450);
FORCEPROP 1 LAST COMMENT_BODY TRUE
J 0
(5175 3275);
DISPLAY 0.872340 (5175 3275);
PAINT PEACH (5175 3275);
DISPLAY INVISIBLE (5175 3275);
FORCEPROP 1 LAST OFFPAGE TRUE
J 0
(5525 3250);
DISPLAY 0.872340 (5525 3250);
PAINT GREEN (5525 3250);
DISPLAY INVISIBLE (5525 3250);
FORCEPROP 2 LAST CDS_LIB standard
J 0
(5200 3375);
DISPLAY INVISIBLE (5200 3375);
FORCEADD OFFPAGE..2
(5200 3325);
FORCEPROP 2 LAST $XR0 15 
J 0
(5389 3325);
DISPLAY 0.638298 (5389 3325);
PAINT MONO (5389 3325);
FORCEPROP 2 LAST $XR1 34 
J 0
(5479 3325);
DISPLAY 0.638298 (5479 3325);
PAINT MONO (5479 3325);
FORCEPROP 2 LAST PATH I126
J 0
(5375 3400);
DISPLAY 1.021277 (5375 3400);
DISPLAY INVISIBLE (5375 3400);
FORCEPROP 1 LAST COMMENT_BODY TRUE
J 0
(5155 3230);
DISPLAY 0.872340 (5155 3230);
PAINT PEACH (5155 3230);
DISPLAY INVISIBLE (5155 3230);
FORCEPROP 1 LAST OFFPAGE TRUE
J 0
(5525 3200);
DISPLAY 0.872340 (5525 3200);
PAINT GREEN (5525 3200);
DISPLAY INVISIBLE (5525 3200);
FORCEPROP 2 LAST CDS_LIB standard
J 0
(5200 3325);
DISPLAY INVISIBLE (5200 3325);
FORCEADD Q_RES..1
(4125 3325);
FORCEPROP 1 LAST VALUE 0
J 2
(4225 3325);
DISPLAY 0.510638 (4225 3325);
PAINT SKYBLUE (4225 3325);
FORCEPROP 1 LAST MATERIAL CHIP
J 0
(4275 3325);
DISPLAY 0.510638 (4275 3325);
PAINT SKYBLUE (4275 3325);
FORCEPROP 1 LAST PART_NUMBER CS00002JB13
J 0
(4025 3400);
DISPLAY 0.510638 (4025 3400);
PAINT WHITE (4025 3400);
DISPLAY INVISIBLE (4025 3400);
FORCEPROP 1 LAST PACK_TYPE 0402LF
J 0
(4100 3375);
DISPLAY 0.510638 (4100 3375);
PAINT SKYBLUE (4100 3375);
DISPLAY INVISIBLE (4100 3375);
FORCEPROP 1 LAST WATTAGE 1/16W
J 2
(4475 3425);
DISPLAY 0.510638 (4475 3425);
PAINT SKYBLUE (4475 3425);
DISPLAY INVISIBLE (4475 3425);
FORCEPROP 1 LAST PATH I128
J 0
(4075 3475);
DISPLAY 0.978723 (4075 3475);
PAINT WHITE (4075 3475);
DISPLAY INVISIBLE (4075 3475);
FORCEPROP 1 LAST TOLERANCE 5%
J 0
(4050 3425);
DISPLAY 0.510638 (4050 3425);
PAINT SKYBLUE (4050 3425);
DISPLAY INVISIBLE (4050 3425);
FORCEPROP 2 LAST CDS_LIB pure_quanta
J 0
(4125 3325);
DISPLAY INVISIBLE (4125 3325);
FORCEPROP 1 LAST LOCATION R566
J 0
(3925 3325);
DISPLAY 0.702128 (3925 3325);
PAINT YELLOW (3925 3325);
FORCEPROP 0 LAST $SEC 1
J 0
(3975 3375);
DISPLAY 0.680851 (3975 3375);
PAINT MONO (3975 3375);
DISPLAY INVISIBLE (3975 3375);
FORCEPROP 0 LAST CDS_SEC 1
J 0
(3975 3375);
DISPLAY 1.021277 (3975 3375);
DISPLAY INVISIBLE (3975 3375);
FORCEPROP 1 LASTPIN (4025 3325) $PN 1
J 0
(4037 3337);
DISPLAY 0.808511 (4037 3337);
PAINT WHITE (4037 3337);
DISPLAY INVISIBLE (4037 3337);
FORCEPROP 1 LASTPIN (4225 3325) $PN 2
J 0
(4187 3337);
DISPLAY 0.808511 (4187 3337);
PAINT WHITE (4187 3337);
DISPLAY INVISIBLE (4187 3337);
FORCEADD OFFPAGE..2
(3150 4025);
FORCEPROP 2 LAST $XR0 23 
J 0
(3339 4025);
DISPLAY 0.638298 (3339 4025);
PAINT MONO (3339 4025);
FORCEPROP 2 LAST PATH I130
J 0
(3350 4075);
DISPLAY 1.021277 (3350 4075);
DISPLAY INVISIBLE (3350 4075);
FORCEPROP 1 LAST COMMENT_BODY TRUE
J 0
(3105 3930);
DISPLAY 0.872340 (3105 3930);
PAINT PEACH (3105 3930);
DISPLAY INVISIBLE (3105 3930);
FORCEPROP 1 LAST OFFPAGE TRUE
J 0
(3475 3900);
DISPLAY 0.872340 (3475 3900);
PAINT GREEN (3475 3900);
DISPLAY INVISIBLE (3475 3900);
FORCEPROP 2 LAST CDS_LIB standard
J 0
(3150 4025);
DISPLAY INVISIBLE (3150 4025);
FORCEADD OFFPAGE..4
(3150 3975);
FORCEPROP 2 LAST $XR0 23 
J 0
(3336 3975);
DISPLAY 0.638298 (3336 3975);
PAINT MONO (3336 3975);
FORCEPROP 1 LAST OFFPAGE TRUE
J 0
(3475 3850);
DISPLAY 1.574468 (3475 3850);
PAINT GREEN (3475 3850);
DISPLAY INVISIBLE (3475 3850);
FORCEPROP 1 LAST COMMENT_BODY TRUE
J 0
(3125 3875);
DISPLAY 1.574468 (3125 3875);
PAINT PEACH (3125 3875);
DISPLAY INVISIBLE (3125 3875);
FORCEPROP 2 LAST PATH I131
J 0
(3350 4025);
DISPLAY 1.021277 (3350 4025);
DISPLAY INVISIBLE (3350 4025);
FORCEPROP 2 LAST CDS_LIB standard
J 0
(3150 3975);
DISPLAY INVISIBLE (3150 3975);
FORCEADD OFFPAGE..2
(3675 4225);
FORCEPROP 2 LAST $XR0 23 
J 0
(3864 4225);
DISPLAY 0.638298 (3864 4225);
PAINT MONO (3864 4225);
FORCEPROP 2 LAST PATH I132
J 0
(3875 4275);
DISPLAY 1.021277 (3875 4275);
DISPLAY INVISIBLE (3875 4275);
FORCEPROP 1 LAST COMMENT_BODY TRUE
J 0
(3630 4130);
DISPLAY 0.872340 (3630 4130);
PAINT PEACH (3630 4130);
DISPLAY INVISIBLE (3630 4130);
FORCEPROP 1 LAST OFFPAGE TRUE
J 0
(4000 4100);
DISPLAY 0.872340 (4000 4100);
PAINT GREEN (4000 4100);
DISPLAY INVISIBLE (4000 4100);
FORCEPROP 2 LAST CDS_LIB standard
J 0
(3675 4225);
DISPLAY INVISIBLE (3675 4225);
FORCEADD Q_RES..1
(3000 4275);
FORCEPROP 1 LAST VALUE 10
J 2
(3175 4275);
DISPLAY 0.510638 (3175 4275);
PAINT SKYBLUE (3175 4275);
FORCEPROP 1 LAST MATERIAL CHIP
J 0
(3200 4275);
DISPLAY 0.510638 (3200 4275);
PAINT SKYBLUE (3200 4275);
FORCEPROP 1 LAST PACK_TYPE 0402LF
J 0
(3250 4125);
DISPLAY 0.510638 (3250 4125);
PAINT SKYBLUE (3250 4125);
DISPLAY INVISIBLE (3250 4125);
FORCEPROP 1 LAST WATTAGE 1/16W
J 2
(2975 4125);
DISPLAY 0.510638 (2975 4125);
PAINT SKYBLUE (2975 4125);
DISPLAY INVISIBLE (2975 4125);
FORCEPROP 1 LAST PATH I133
J 0
(2950 4425);
DISPLAY 0.978723 (2950 4425);
PAINT WHITE (2950 4425);
DISPLAY INVISIBLE (2950 4425);
FORCEPROP 2 LAST CDS_LIB pure_quanta
J 0
(3000 4275);
DISPLAY INVISIBLE (3000 4275);
FORCEPROP 1 LAST TOLERANCE 1%
J 0
(3000 4175);
DISPLAY 0.510638 (3000 4175);
PAINT SKYBLUE (3000 4175);
DISPLAY INVISIBLE (3000 4175);
FORCEPROP 1 LAST PART_NUMBER CS01002FB07
J 0
(2950 4375);
DISPLAY 0.510638 (2950 4375);
PAINT WHITE (2950 4375);
DISPLAY INVISIBLE (2950 4375);
FORCEPROP 1 LAST LOCATION R21
J 0
(2825 4275);
DISPLAY 0.702128 (2825 4275);
PAINT YELLOW (2825 4275);
FORCEPROP 1 LASTPIN (2900 4275) $PN 1
J 0
(2912 4287);
DISPLAY 0.808511 (2912 4287);
PAINT WHITE (2912 4287);
FORCEPROP 1 LASTPIN (3100 4275) $PN 2
J 0
(3062 4287);
DISPLAY 0.808511 (3062 4287);
PAINT WHITE (3062 4287);
FORCEPROP 2 LAST $SEC 1
J 0
(2950 4475);
DISPLAY 0.680851 (2950 4475);
PAINT MONO (2950 4475);
DISPLAY INVISIBLE (2950 4475);
FORCEPROP 0 LAST CDS_SEC 1
J 0
(2950 4475);
DISPLAY 0.680851 (2950 4475);
PAINT MONO (2950 4475);
DISPLAY INVISIBLE (2950 4475);
FORCEADD Q_RES..1
(3000 4325);
FORCEPROP 1 LAST WATTAGE 1/16W
J 2
(3225 4375);
DISPLAY 0.510638 (3225 4375);
PAINT SKYBLUE (3225 4375);
FORCEPROP 1 LAST PACK_TYPE 0402LF
J 0
(2850 4400);
DISPLAY 0.510638 (2850 4400);
PAINT SKYBLUE (2850 4400);
FORCEPROP 1 LAST VALUE 10
J 2
(3175 4325);
DISPLAY 0.510638 (3175 4325);
PAINT SKYBLUE (3175 4325);
FORCEPROP 1 LAST MATERIAL CHIP
J 0
(3200 4325);
DISPLAY 0.510638 (3200 4325);
PAINT SKYBLUE (3200 4325);
FORCEPROP 1 LAST PART_NUMBER CS01002FB07
J 0
(2850 4450);
DISPLAY 0.510638 (2850 4450);
PAINT WHITE (2850 4450);
FORCEPROP 1 LAST TOLERANCE 1%
J 0
(3250 4375);
DISPLAY 0.510638 (3250 4375);
PAINT SKYBLUE (3250 4375);
FORCEPROP 2 LAST CDS_LIB pure_quanta
J 0
(3000 4325);
DISPLAY INVISIBLE (3000 4325);
FORCEPROP 1 LAST PATH I134
J 0
(2950 4475);
DISPLAY 0.978723 (2950 4475);
PAINT WHITE (2950 4475);
DISPLAY INVISIBLE (2950 4475);
FORCEPROP 1 LAST LOCATION R24
J 0
(2825 4325);
DISPLAY 0.702128 (2825 4325);
PAINT YELLOW (2825 4325);
FORCEPROP 1 LASTPIN (2900 4325) $PN 1
J 0
(2912 4337);
DISPLAY 0.808511 (2912 4337);
PAINT WHITE (2912 4337);
FORCEPROP 1 LASTPIN (3100 4325) $PN 2
J 0
(3062 4337);
DISPLAY 0.808511 (3062 4337);
PAINT WHITE (3062 4337);
FORCEPROP 2 LAST $SEC 1
J 0
(2950 4525);
DISPLAY 0.680851 (2950 4525);
PAINT MONO (2950 4525);
DISPLAY INVISIBLE (2950 4525);
FORCEPROP 0 LAST CDS_SEC 1
J 0
(2950 4525);
DISPLAY 0.680851 (2950 4525);
PAINT MONO (2950 4525);
DISPLAY INVISIBLE (2950 4525);
FORCEADD OFFPAGE..2
(3125 4525);
FORCEPROP 2 LAST $XR0 15 
J 0
(3314 4525);
DISPLAY 0.638298 (3314 4525);
PAINT MONO (3314 4525);
FORCEPROP 2 LAST PATH I135
J 0
(3325 4575);
DISPLAY 1.021277 (3325 4575);
DISPLAY INVISIBLE (3325 4575);
FORCEPROP 1 LAST COMMENT_BODY TRUE
J 0
(3080 4430);
DISPLAY 0.872340 (3080 4430);
PAINT PEACH (3080 4430);
DISPLAY INVISIBLE (3080 4430);
FORCEPROP 1 LAST OFFPAGE TRUE
J 0
(3450 4400);
DISPLAY 0.872340 (3450 4400);
PAINT GREEN (3450 4400);
DISPLAY INVISIBLE (3450 4400);
FORCEPROP 2 LAST CDS_LIB standard
J 0
(3125 4525);
DISPLAY INVISIBLE (3125 4525);
FORCEADD OFFPAGE..2
(3125 4575);
FORCEPROP 2 LAST $XR0 15 
J 0
(3314 4575);
DISPLAY 0.638298 (3314 4575);
PAINT MONO (3314 4575);
FORCEPROP 2 LAST PATH I136
J 0
(3325 4625);
DISPLAY 1.021277 (3325 4625);
DISPLAY INVISIBLE (3325 4625);
FORCEPROP 1 LAST COMMENT_BODY TRUE
J 0
(3080 4480);
DISPLAY 0.872340 (3080 4480);
PAINT PEACH (3080 4480);
DISPLAY INVISIBLE (3080 4480);
FORCEPROP 1 LAST OFFPAGE TRUE
J 0
(3450 4450);
DISPLAY 0.872340 (3450 4450);
PAINT GREEN (3450 4450);
DISPLAY INVISIBLE (3450 4450);
FORCEPROP 2 LAST CDS_LIB standard
J 0
(3125 4575);
DISPLAY INVISIBLE (3125 4575);
FORCEADD OFFPAGE..2
(3125 4625);
FORCEPROP 2 LAST $XR0 15 
J 0
(3314 4625);
DISPLAY 0.638298 (3314 4625);
PAINT MONO (3314 4625);
FORCEPROP 2 LAST CDS_LIB standard
J 0
(3125 4625);
DISPLAY INVISIBLE (3125 4625);
FORCEPROP 2 LAST PATH I137
J 0
(3325 4675);
DISPLAY 1.021277 (3325 4675);
DISPLAY INVISIBLE (3325 4675);
FORCEPROP 1 LAST OFFPAGE TRUE
J 0
(3450 4500);
DISPLAY 0.872340 (3450 4500);
PAINT GREEN (3450 4500);
DISPLAY INVISIBLE (3450 4500);
FORCEPROP 1 LAST COMMENT_BODY TRUE
J 0
(3080 4530);
DISPLAY 0.872340 (3080 4530);
PAINT PEACH (3080 4530);
DISPLAY INVISIBLE (3080 4530);
FORCEADD OFFPAGE..2
(3675 4275);
FORCEPROP 2 LAST $XR0 23 
J 0
(3864 4275);
DISPLAY 0.638298 (3864 4275);
PAINT MONO (3864 4275);
FORCEPROP 2 LAST PATH I138
J 0
(3875 4325);
DISPLAY 1.021277 (3875 4325);
DISPLAY INVISIBLE (3875 4325);
FORCEPROP 1 LAST COMMENT_BODY TRUE
J 0
(3630 4180);
DISPLAY 0.872340 (3630 4180);
PAINT PEACH (3630 4180);
DISPLAY INVISIBLE (3630 4180);
FORCEPROP 1 LAST OFFPAGE TRUE
J 0
(4000 4150);
DISPLAY 0.872340 (4000 4150);
PAINT GREEN (4000 4150);
DISPLAY INVISIBLE (4000 4150);
FORCEPROP 2 LAST CDS_LIB standard
J 0
(3675 4275);
DISPLAY INVISIBLE (3675 4275);
FORCEADD OFFPAGE..2
(3675 4325);
FORCEPROP 2 LAST $XR0 23 
J 0
(3864 4325);
DISPLAY 0.638298 (3864 4325);
PAINT MONO (3864 4325);
FORCEPROP 2 LAST PATH I139
J 0
(3875 4375);
DISPLAY 1.021277 (3875 4375);
DISPLAY INVISIBLE (3875 4375);
FORCEPROP 1 LAST COMMENT_BODY TRUE
J 0
(3630 4230);
DISPLAY 0.872340 (3630 4230);
PAINT PEACH (3630 4230);
DISPLAY INVISIBLE (3630 4230);
FORCEPROP 1 LAST OFFPAGE TRUE
J 0
(4000 4200);
DISPLAY 0.872340 (4000 4200);
PAINT GREEN (4000 4200);
DISPLAY INVISIBLE (4000 4200);
FORCEPROP 2 LAST CDS_LIB standard
J 0
(3675 4325);
DISPLAY INVISIBLE (3675 4325);
FORCEADD Q_CAP..1
(3175 -725);
FORCEPROP 1 LAST TOLERANCE 10%
J 0
(3225 -775);
DISPLAY 0.510638 (3225 -775);
PAINT SKYBLUE (3225 -775);
FORCEPROP 1 LAST VOLTAGE 25V
J 0
(3225 -725);
DISPLAY 0.510638 (3225 -725);
PAINT SKYBLUE (3225 -725);
FORCEPROP 1 LAST PACK_TYPE C0402
J 0
(3200 -875);
DISPLAY 0.510638 (3200 -875);
PAINT SKYBLUE (3200 -875);
FORCEPROP 1 LAST MATERIAL X6S
J 0
(3225 -825);
DISPLAY 0.510638 (3225 -825);
PAINT SKYBLUE (3225 -825);
FORCEPROP 1 LAST VALUE 1UF
J 0
(3225 -675);
DISPLAY 0.510638 (3225 -675);
PAINT SKYBLUE (3225 -675);
FORCEPROP 1 LAST PATH I14
J 0
(3225 -575);
DISPLAY 0.978723 (3225 -575);
PAINT WHITE (3225 -575);
DISPLAY INVISIBLE (3225 -575);
FORCEPROP 2 LAST CDS_LIB pure_quanta
J 0
(3175 -725);
DISPLAY INVISIBLE (3175 -725);
FORCEPROP 1 LAST PART_NUMBER CH5104KEB02
J 0
(3225 -875);
DISPLAY 0.510638 (3225 -875);
PAINT WHITE (3225 -875);
DISPLAY INVISIBLE (3225 -875);
FORCEPROP 1 LAST LOCATION C35
J 0
(3225 -625);
DISPLAY 0.702128 (3225 -625);
PAINT YELLOW (3225 -625);
FORCEPROP 1 LASTPIN (3175 -625) $PN 1
J 0
(3185 -645);
DISPLAY 0.808511 (3185 -645);
PAINT WHITE (3185 -645);
FORCEPROP 1 LASTPIN (3175 -825) $PN 2
J 0
(3185 -845);
DISPLAY 0.808511 (3185 -845);
PAINT WHITE (3185 -845);
FORCEPROP 2 LAST $SEC 1
J 0
(3225 -525);
DISPLAY 0.680851 (3225 -525);
PAINT MONO (3225 -525);
DISPLAY INVISIBLE (3225 -525);
FORCEPROP 0 LAST CDS_SEC 1
J 0
(3225 -525);
DISPLAY 0.680851 (3225 -525);
PAINT MONO (3225 -525);
DISPLAY INVISIBLE (3225 -525);
FORCEADD Q_RES..1
(2975 4075);
FORCEPROP 1 LAST MATERIAL CHIP
J 0
(3175 4075);
DISPLAY 0.510638 (3175 4075);
PAINT SKYBLUE (3175 4075);
FORCEPROP 1 LAST VALUE 0
J 2
(3150 4075);
DISPLAY 0.510638 (3150 4075);
PAINT SKYBLUE (3150 4075);
FORCEPROP 1 LAST PART_NUMBER CS00002JB13
J 0
(2925 4175);
DISPLAY 0.510638 (2925 4175);
PAINT WHITE (2925 4175);
DISPLAY INVISIBLE (2925 4175);
FORCEPROP 1 LAST PACK_TYPE 0402LF
J 0
(3225 3925);
DISPLAY 0.510638 (3225 3925);
PAINT SKYBLUE (3225 3925);
DISPLAY INVISIBLE (3225 3925);
FORCEPROP 1 LAST WATTAGE 1/16W
J 2
(2950 3925);
DISPLAY 0.510638 (2950 3925);
PAINT SKYBLUE (2950 3925);
DISPLAY INVISIBLE (2950 3925);
FORCEPROP 1 LAST PATH I140
J 0
(2925 4225);
DISPLAY 0.978723 (2925 4225);
PAINT WHITE (2925 4225);
DISPLAY INVISIBLE (2925 4225);
FORCEPROP 1 LAST TOLERANCE 5%
J 0
(2975 3975);
DISPLAY 0.510638 (2975 3975);
PAINT SKYBLUE (2975 3975);
DISPLAY INVISIBLE (2975 3975);
FORCEPROP 2 LAST CDS_LIB pure_quanta
J 0
(2975 4075);
DISPLAY INVISIBLE (2975 4075);
FORCEPROP 1 LAST LOCATION R20
J 0
(2800 4075);
DISPLAY 0.702128 (2800 4075);
PAINT YELLOW (2800 4075);
FORCEPROP 0 LAST $SEC 1
J 0
(2900 4125);
DISPLAY INVISIBLE (2900 4125);
FORCEPROP 0 LAST CDS_SEC 1
J 0
(2900 4125);
DISPLAY INVISIBLE (2900 4125);
FORCEPROP 1 LASTPIN (2875 4075) $PN 1
J 0
(2887 4087);
DISPLAY 0.808511 (2887 4087);
PAINT WHITE (2887 4087);
DISPLAY INVISIBLE (2887 4087);
FORCEPROP 1 LASTPIN (3075 4075) $PN 2
J 0
(3037 4087);
DISPLAY 0.808511 (3037 4087);
PAINT WHITE (3037 4087);
DISPLAY INVISIBLE (3037 4087);
FORCEADD Q_RES..1
(2975 4125);
FORCEPROP 1 LAST VALUE 0
J 2
(3150 4125);
DISPLAY 0.510638 (3150 4125);
PAINT SKYBLUE (3150 4125);
FORCEPROP 1 LAST MATERIAL CHIP
J 0
(3175 4125);
DISPLAY 0.510638 (3175 4125);
PAINT SKYBLUE (3175 4125);
FORCEPROP 1 LAST PART_NUMBER CS00002JB13
J 0
(2925 4225);
DISPLAY 0.510638 (2925 4225);
PAINT WHITE (2925 4225);
DISPLAY INVISIBLE (2925 4225);
FORCEPROP 1 LAST PACK_TYPE 0402LF
J 0
(3225 3975);
DISPLAY 0.510638 (3225 3975);
PAINT SKYBLUE (3225 3975);
DISPLAY INVISIBLE (3225 3975);
FORCEPROP 1 LAST WATTAGE 1/16W
J 2
(2950 3975);
DISPLAY 0.510638 (2950 3975);
PAINT SKYBLUE (2950 3975);
DISPLAY INVISIBLE (2950 3975);
FORCEPROP 1 LAST PATH I141
J 0
(2925 4275);
DISPLAY 0.978723 (2925 4275);
PAINT WHITE (2925 4275);
DISPLAY INVISIBLE (2925 4275);
FORCEPROP 1 LAST TOLERANCE 5%
J 0
(2975 4025);
DISPLAY 0.510638 (2975 4025);
PAINT SKYBLUE (2975 4025);
DISPLAY INVISIBLE (2975 4025);
FORCEPROP 2 LAST CDS_LIB pure_quanta
J 0
(2975 4125);
DISPLAY INVISIBLE (2975 4125);
FORCEPROP 1 LAST LOCATION R19
J 0
(2800 4125);
DISPLAY 0.702128 (2800 4125);
PAINT YELLOW (2800 4125);
FORCEPROP 0 LAST $SEC 1
J 0
(2900 4200);
DISPLAY INVISIBLE (2900 4200);
FORCEPROP 0 LAST CDS_SEC 1
J 0
(2900 4200);
DISPLAY INVISIBLE (2900 4200);
FORCEPROP 1 LASTPIN (2875 4125) $PN 1
J 0
(2887 4137);
DISPLAY 0.808511 (2887 4137);
PAINT WHITE (2887 4137);
DISPLAY INVISIBLE (2887 4137);
FORCEPROP 1 LASTPIN (3075 4125) $PN 2
J 0
(3037 4137);
DISPLAY 0.808511 (3037 4137);
PAINT WHITE (3037 4137);
DISPLAY INVISIBLE (3037 4137);
FORCEADD Q_RES..1
(3000 4225);
FORCEPROP 1 LAST VALUE 10
J 2
(3175 4225);
DISPLAY 0.510638 (3175 4225);
PAINT SKYBLUE (3175 4225);
FORCEPROP 1 LAST MATERIAL CHIP
J 0
(3200 4225);
DISPLAY 0.510638 (3200 4225);
PAINT SKYBLUE (3200 4225);
FORCEPROP 1 LAST PART_NUMBER CS01002FB07
J 0
(2950 4325);
DISPLAY 0.510638 (2950 4325);
PAINT WHITE (2950 4325);
DISPLAY INVISIBLE (2950 4325);
FORCEPROP 1 LAST TOLERANCE 1%
J 0
(3000 4125);
DISPLAY 0.510638 (3000 4125);
PAINT SKYBLUE (3000 4125);
DISPLAY INVISIBLE (3000 4125);
FORCEPROP 2 LAST CDS_LIB pure_quanta
J 0
(3000 4225);
DISPLAY INVISIBLE (3000 4225);
FORCEPROP 1 LAST PATH I142
J 0
(2950 4375);
DISPLAY 0.978723 (2950 4375);
PAINT WHITE (2950 4375);
DISPLAY INVISIBLE (2950 4375);
FORCEPROP 1 LAST WATTAGE 1/16W
J 2
(2975 4075);
DISPLAY 0.510638 (2975 4075);
PAINT SKYBLUE (2975 4075);
DISPLAY INVISIBLE (2975 4075);
FORCEPROP 1 LAST PACK_TYPE 0402LF
J 0
(3250 4075);
DISPLAY 0.510638 (3250 4075);
PAINT SKYBLUE (3250 4075);
DISPLAY INVISIBLE (3250 4075);
FORCEPROP 1 LAST LOCATION R26
J 0
(2825 4225);
DISPLAY 0.702128 (2825 4225);
PAINT YELLOW (2825 4225);
FORCEPROP 1 LASTPIN (2900 4225) $PN 1
J 0
(2912 4237);
DISPLAY 0.808511 (2912 4237);
PAINT WHITE (2912 4237);
FORCEPROP 1 LASTPIN (3100 4225) $PN 2
J 0
(3062 4237);
DISPLAY 0.808511 (3062 4237);
PAINT WHITE (3062 4237);
FORCEPROP 2 LAST $SEC 1
J 0
(2950 4425);
DISPLAY 0.680851 (2950 4425);
PAINT MONO (2950 4425);
DISPLAY INVISIBLE (2950 4425);
FORCEPROP 0 LAST CDS_SEC 1
J 0
(2950 4425);
DISPLAY 0.680851 (2950 4425);
PAINT MONO (2950 4425);
DISPLAY INVISIBLE (2950 4425);
FORCEADD OFFPAGE..2
(3675 4075);
FORCEPROP 2 LAST $XR0 23 
J 0
(3864 4075);
DISPLAY 0.638298 (3864 4075);
PAINT MONO (3864 4075);
FORCEPROP 2 LAST PATH I143
J 0
(3875 4125);
DISPLAY 1.021277 (3875 4125);
DISPLAY INVISIBLE (3875 4125);
FORCEPROP 1 LAST COMMENT_BODY TRUE
J 0
(3630 3980);
DISPLAY 0.872340 (3630 3980);
PAINT PEACH (3630 3980);
DISPLAY INVISIBLE (3630 3980);
FORCEPROP 1 LAST OFFPAGE TRUE
J 0
(4000 3950);
DISPLAY 0.872340 (4000 3950);
PAINT GREEN (4000 3950);
DISPLAY INVISIBLE (4000 3950);
FORCEPROP 2 LAST CDS_LIB standard
J 0
(3675 4075);
DISPLAY INVISIBLE (3675 4075);
FORCEADD OFFPAGE..2
(3675 4125);
FORCEPROP 2 LAST $XR0 23 
J 0
(3864 4125);
DISPLAY 0.638298 (3864 4125);
PAINT MONO (3864 4125);
FORCEPROP 2 LAST PATH I144
J 0
(3875 4175);
DISPLAY 1.021277 (3875 4175);
DISPLAY INVISIBLE (3875 4175);
FORCEPROP 1 LAST COMMENT_BODY TRUE
J 0
(3630 4030);
DISPLAY 0.872340 (3630 4030);
PAINT PEACH (3630 4030);
DISPLAY INVISIBLE (3630 4030);
FORCEPROP 1 LAST OFFPAGE TRUE
J 0
(4000 4000);
DISPLAY 0.872340 (4000 4000);
PAINT GREEN (4000 4000);
DISPLAY INVISIBLE (4000 4000);
FORCEPROP 2 LAST CDS_LIB standard
J 0
(3675 4125);
DISPLAY INVISIBLE (3675 4125);
FORCEADD OFFPAGE..1
(4850 4275);
FORCEPROP 2 LAST $XR0 15 
J 0
(4629 4275);
DISPLAY 0.638298 (4629 4275);
PAINT MONO (4629 4275);
FORCEPROP 2 LAST PATH I145
J 0
(4650 4325);
DISPLAY 1.021277 (4650 4325);
DISPLAY INVISIBLE (4650 4325);
FORCEPROP 1 LAST COMMENT_BODY TRUE
J 0
(4975 4175);
DISPLAY 0.872340 (4975 4175);
PAINT PEACH (4975 4175);
DISPLAY INVISIBLE (4975 4175);
FORCEPROP 1 LAST OFFPAGE TRUE
J 0
(5175 4150);
DISPLAY 0.872340 (5175 4150);
PAINT GREEN (5175 4150);
DISPLAY INVISIBLE (5175 4150);
FORCEPROP 2 LAST CDS_LIB standard
J 0
(4850 4275);
DISPLAY INVISIBLE (4850 4275);
FORCEADD OFFPAGE..1
(4850 4175);
FORCEPROP 2 LAST $XR0 15 
J 0
(4629 4175);
DISPLAY 0.638298 (4629 4175);
PAINT MONO (4629 4175);
FORCEPROP 2 LAST PATH I146
J 0
(4650 4225);
DISPLAY 1.021277 (4650 4225);
DISPLAY INVISIBLE (4650 4225);
FORCEPROP 1 LAST COMMENT_BODY TRUE
J 0
(4975 4075);
DISPLAY 0.872340 (4975 4075);
PAINT PEACH (4975 4075);
DISPLAY INVISIBLE (4975 4075);
FORCEPROP 1 LAST OFFPAGE TRUE
J 0
(5175 4050);
DISPLAY 0.872340 (5175 4050);
PAINT GREEN (5175 4050);
DISPLAY INVISIBLE (5175 4050);
FORCEPROP 2 LAST CDS_LIB standard
J 0
(4850 4175);
DISPLAY INVISIBLE (4850 4175);
FORCEADD OFFPAGE..1
(4850 4375);
FORCEPROP 2 LAST $XR0 15 
J 0
(4629 4375);
DISPLAY 0.638298 (4629 4375);
PAINT MONO (4629 4375);
FORCEPROP 2 LAST PATH I147
J 0
(4650 4425);
DISPLAY 1.021277 (4650 4425);
DISPLAY INVISIBLE (4650 4425);
FORCEPROP 1 LAST COMMENT_BODY TRUE
J 0
(4975 4275);
DISPLAY 0.872340 (4975 4275);
PAINT PEACH (4975 4275);
DISPLAY INVISIBLE (4975 4275);
FORCEPROP 1 LAST OFFPAGE TRUE
J 0
(5175 4250);
DISPLAY 0.872340 (5175 4250);
PAINT GREEN (5175 4250);
DISPLAY INVISIBLE (5175 4250);
FORCEPROP 2 LAST CDS_LIB standard
J 0
(4850 4375);
DISPLAY INVISIBLE (4850 4375);
FORCEADD UNIVERSAL_GND..1
(6100 4025);
FORCEPROP 3 LASTPIN (6100 4075) SIG_NAME GND\g
J 0
(6110 4085);
DISPLAY 0.659574 (6110 4085);
PAINT MONO (6110 4085);
DISPLAY INVISIBLE (6110 4085);
FORCEPROP 1 LAST PATH I148
J 0
(6175 4025);
DISPLAY 0.872340 (6175 4025);
PAINT AQUA (6175 4025);
DISPLAY INVISIBLE (6175 4025);
FORCEPROP 1 LAST HDL_POWER GND
J 1
(6125 3950);
DISPLAY 0.702128 (6125 3950);
PAINT GREEN (6125 3950);
DISPLAY INVISIBLE (6125 3950);
FORCEPROP 2 LAST CDS_LIB logical_power
J 0
(6100 4025);
DISPLAY INVISIBLE (6100 4025);
FORCEADD Q_RES..1
(5600 4175);
FORCEPROP 1 LAST VALUE 150
J 2
(5875 4175);
DISPLAY 0.510638 (5875 4175);
PAINT SKYBLUE (5875 4175);
FORCEPROP 1 LAST MATERIAL CHIP
J 0
(5925 4175);
DISPLAY 0.510638 (5925 4175);
PAINT SKYBLUE (5925 4175);
FORCEPROP 1 LAST PART_NUMBER CS11502FB07
J 0
(5550 4325);
DISPLAY 0.510638 (5550 4325);
PAINT WHITE (5550 4325);
DISPLAY INVISIBLE (5550 4325);
FORCEPROP 1 LAST PACK_TYPE 0402LF
J 0
(6125 4250);
DISPLAY 0.510638 (6125 4250);
PAINT SKYBLUE (6125 4250);
DISPLAY INVISIBLE (6125 4250);
FORCEPROP 1 LAST WATTAGE 1/16W
J 2
(5875 4250);
DISPLAY 0.510638 (5875 4250);
PAINT SKYBLUE (5875 4250);
DISPLAY INVISIBLE (5875 4250);
FORCEPROP 1 LAST PATH I149
J 0
(5550 4325);
DISPLAY 0.978723 (5550 4325);
PAINT WHITE (5550 4325);
DISPLAY INVISIBLE (5550 4325);
FORCEPROP 1 LAST TOLERANCE 1%
J 0
(6450 4250);
DISPLAY 0.510638 (6450 4250);
PAINT SKYBLUE (6450 4250);
DISPLAY INVISIBLE (6450 4250);
FORCEPROP 2 LAST CDS_LIB pure_quanta
J 0
(5600 4175);
DISPLAY INVISIBLE (5600 4175);
FORCEPROP 1 LAST LOCATION R25
J 0
(5325 4175);
DISPLAY 0.702128 (5325 4175);
PAINT YELLOW (5325 4175);
FORCEPROP 1 LASTPIN (5500 4175) $PN 1
J 0
(5512 4187);
DISPLAY 0.808511 (5512 4187);
PAINT WHITE (5512 4187);
FORCEPROP 1 LASTPIN (5700 4175) $PN 2
J 0
(5662 4187);
DISPLAY 0.808511 (5662 4187);
PAINT WHITE (5662 4187);
FORCEPROP 0 LAST $SEC 1
J 0
(5875 4225);
DISPLAY 0.680851 (5875 4225);
PAINT MONO (5875 4225);
DISPLAY INVISIBLE (5875 4225);
FORCEPROP 0 LAST CDS_SEC 1
J 0
(5875 4225);
DISPLAY 0.680851 (5875 4225);
DISPLAY INVISIBLE (5875 4225);
FORCEADD UNIVERSAL_GND..1
(3250 -1000);
FORCEPROP 3 LASTPIN (3250 -950) SIG_NAME GND\g
J 0
(3260 -940);
DISPLAY 0.659574 (3260 -940);
PAINT MONO (3260 -940);
DISPLAY INVISIBLE (3260 -940);
FORCEPROP 1 LAST PATH I15
J 0
(3325 -1000);
DISPLAY 0.872340 (3325 -1000);
PAINT AQUA (3325 -1000);
DISPLAY INVISIBLE (3325 -1000);
FORCEPROP 1 LAST HDL_POWER GND
J 1
(3275 -1075);
DISPLAY 0.702128 (3275 -1075);
PAINT GREEN (3275 -1075);
DISPLAY INVISIBLE (3275 -1075);
FORCEPROP 2 LAST CDS_LIB logical_power
J 0
(3250 -1000);
DISPLAY INVISIBLE (3250 -1000);
FORCEADD Q_RES..1
(5600 4275);
FORCEPROP 1 LAST VALUE 150
J 2
(5875 4275);
DISPLAY 0.510638 (5875 4275);
PAINT SKYBLUE (5875 4275);
FORCEPROP 1 LAST MATERIAL CHIP
J 0
(5925 4275);
DISPLAY 0.510638 (5925 4275);
PAINT SKYBLUE (5925 4275);
FORCEPROP 1 LAST PART_NUMBER CS11502FB07
J 0
(5550 4425);
DISPLAY 0.510638 (5550 4425);
PAINT WHITE (5550 4425);
DISPLAY INVISIBLE (5550 4425);
FORCEPROP 1 LAST PACK_TYPE 0402LF
J 0
(6125 4350);
DISPLAY 0.510638 (6125 4350);
PAINT SKYBLUE (6125 4350);
DISPLAY INVISIBLE (6125 4350);
FORCEPROP 1 LAST WATTAGE 1/16W
J 2
(5875 4350);
DISPLAY 0.510638 (5875 4350);
PAINT SKYBLUE (5875 4350);
DISPLAY INVISIBLE (5875 4350);
FORCEPROP 1 LAST PATH I150
J 0
(5550 4425);
DISPLAY 0.978723 (5550 4425);
PAINT WHITE (5550 4425);
DISPLAY INVISIBLE (5550 4425);
FORCEPROP 1 LAST TOLERANCE 1%
J 0
(6450 4350);
DISPLAY 0.510638 (6450 4350);
PAINT SKYBLUE (6450 4350);
DISPLAY INVISIBLE (6450 4350);
FORCEPROP 2 LAST CDS_LIB pure_quanta
J 0
(5600 4275);
DISPLAY INVISIBLE (5600 4275);
FORCEPROP 1 LAST LOCATION R23
J 0
(5325 4275);
DISPLAY 0.702128 (5325 4275);
PAINT YELLOW (5325 4275);
FORCEPROP 1 LASTPIN (5500 4275) $PN 1
J 0
(5512 4287);
DISPLAY 0.808511 (5512 4287);
PAINT WHITE (5512 4287);
FORCEPROP 1 LASTPIN (5700 4275) $PN 2
J 0
(5662 4287);
DISPLAY 0.808511 (5662 4287);
PAINT WHITE (5662 4287);
FORCEPROP 0 LAST $SEC 1
J 0
(5875 4325);
DISPLAY 0.680851 (5875 4325);
PAINT MONO (5875 4325);
DISPLAY INVISIBLE (5875 4325);
FORCEPROP 0 LAST CDS_SEC 1
J 0
(5875 4325);
DISPLAY 0.680851 (5875 4325);
DISPLAY INVISIBLE (5875 4325);
FORCEADD Q_RES..1
(5600 4375);
FORCEPROP 1 LAST WATTAGE 1/16W
J 2
(5700 4475);
DISPLAY 0.510638 (5700 4475);
PAINT SKYBLUE (5700 4475);
FORCEPROP 1 LAST PART_NUMBER CS11502FB07
J 0
(5550 4525);
DISPLAY 0.510638 (5550 4525);
PAINT WHITE (5550 4525);
FORCEPROP 1 LAST VALUE 150
J 2
(5875 4375);
DISPLAY 0.510638 (5875 4375);
PAINT SKYBLUE (5875 4375);
FORCEPROP 1 LAST PACK_TYPE 0402LF
J 0
(5900 4475);
DISPLAY 0.510638 (5900 4475);
PAINT SKYBLUE (5900 4475);
FORCEPROP 1 LAST MATERIAL CHIP
J 0
(5925 4375);
DISPLAY 0.510638 (5925 4375);
PAINT SKYBLUE (5925 4375);
FORCEPROP 1 LAST TOLERANCE 1%
J 0
(6075 4475);
DISPLAY 0.510638 (6075 4475);
PAINT SKYBLUE (6075 4475);
FORCEPROP 1 LAST PATH I151
J 0
(5550 4525);
DISPLAY 0.978723 (5550 4525);
PAINT WHITE (5550 4525);
DISPLAY INVISIBLE (5550 4525);
FORCEPROP 2 LAST CDS_LIB pure_quanta
J 0
(5600 4375);
DISPLAY INVISIBLE (5600 4375);
FORCEPROP 1 LAST LOCATION R22
J 0
(5325 4375);
DISPLAY 0.702128 (5325 4375);
PAINT YELLOW (5325 4375);
FORCEPROP 1 LASTPIN (5500 4375) $PN 1
J 0
(5512 4387);
DISPLAY 0.808511 (5512 4387);
PAINT WHITE (5512 4387);
FORCEPROP 1 LASTPIN (5700 4375) $PN 2
J 0
(5662 4387);
DISPLAY 0.808511 (5662 4387);
PAINT WHITE (5662 4387);
FORCEPROP 0 LAST $SEC 1
J 0
(5550 4575);
DISPLAY 0.680851 (5550 4575);
PAINT MONO (5550 4575);
DISPLAY INVISIBLE (5550 4575);
FORCEPROP 0 LAST CDS_SEC 1
J 0
(5550 4575);
DISPLAY 0.680851 (5550 4575);
DISPLAY INVISIBLE (5550 4575);
FORCEADD Q_RES..2
(-2900 4275);
FORCEPROP 1 LAST VALUE 4.7K
J 0
(-2850 4300);
DISPLAY 0.510638 (-2850 4300);
PAINT SKYBLUE (-2850 4300);
FORCEPROP 1 LAST TOLERANCE 1%
J 0
(-2850 4250);
DISPLAY 0.510638 (-2850 4250);
PAINT SKYBLUE (-2850 4250);
FORCEPROP 1 LAST MATERIAL EMPTY
J 0
(-2850 4200);
DISPLAY 0.510638 (-2850 4200);
PAINT RED (-2850 4200);
FORCEPROP 1 LAST PART_NUMBER CS24702FB06
J 0
(-2860 4150);
DISPLAY 0.510638 (-2860 4150);
PAINT WHITE (-2860 4150);
DISPLAY INVISIBLE (-2860 4150);
FORCEPROP 1 LAST PACK_TYPE 0402LF
J 0
(-2860 4100);
DISPLAY 0.510638 (-2860 4100);
PAINT SKYBLUE (-2860 4100);
DISPLAY INVISIBLE (-2860 4100);
FORCEPROP 1 LAST WATTAGE 1/16W
J 0
(-2860 4250);
DISPLAY 0.510638 (-2860 4250);
PAINT SKYBLUE (-2860 4250);
DISPLAY INVISIBLE (-2860 4250);
FORCEPROP 1 LAST PATH I152
J 0
(-2850 4450);
DISPLAY 0.978723 (-2850 4450);
PAINT WHITE (-2850 4450);
DISPLAY INVISIBLE (-2850 4450);
FORCEPROP 2 LAST CDS_LIB pure_quanta
J 0
(-2900 4275);
DISPLAY INVISIBLE (-2900 4275);
FORCEPROP 1 LAST LOCATION R623
J 0
(-2850 4350);
DISPLAY 0.702128 (-2850 4350);
PAINT YELLOW (-2850 4350);
FORCEPROP 1 LASTPIN (-2900 4375) $PN 1
J 0
(-2895 4337);
DISPLAY 0.808511 (-2895 4337);
PAINT WHITE (-2895 4337);
FORCEPROP 1 LASTPIN (-2900 4175) $PN 2
J 0
(-2895 4185);
DISPLAY 0.808511 (-2895 4185);
PAINT WHITE (-2895 4185);
FORCEPROP 0 LAST $SEC 1
J 0
(-2850 4450);
DISPLAY 0.680851 (-2850 4450);
PAINT MONO (-2850 4450);
DISPLAY INVISIBLE (-2850 4450);
FORCEPROP 0 LAST CDS_SEC 1
J 0
(-2850 4450);
DISPLAY 0.680851 (-2850 4450);
DISPLAY INVISIBLE (-2850 4450);
FORCEADD UNIVERSAL_POWER..1
(-2900 4500);
FORCEPROP 3 LASTPIN (-2900 4450) SIG_NAME P3V3_RGM\g
J 0
(-2890 4460);
DISPLAY 0.659574 (-2890 4460);
PAINT MONO (-2890 4460);
DISPLAY INVISIBLE (-2890 4460);
FORCEPROP 1 LAST HDL_POWER P3V3_RGM
J 1
(-2900 4550);
DISPLAY 0.702128 (-2900 4550);
PAINT GREEN (-2900 4550);
FORCEPROP 1 LAST PATH I154
J 0
(-2850 4525);
DISPLAY 0.872340 (-2850 4525);
PAINT AQUA (-2850 4525);
DISPLAY INVISIBLE (-2850 4525);
FORCEPROP 2 LAST CDS_LIB logical_power
J 0
(-2900 4500);
DISPLAY INVISIBLE (-2900 4500);
FORCEADD OFFPAGE..2
(-2000 4075);
FORCEPROP 2 LAST $XR0 22 
J 0
(-1811 4075);
DISPLAY 0.638298 (-1811 4075);
PAINT MONO (-1811 4075);
FORCEPROP 2 LAST $XR2 15 
J 0
(-1631 4075);
DISPLAY 0.638298 (-1631 4075);
PAINT MONO (-1631 4075);
FORCEPROP 2 LAST $XR1 34 
J 0
(-1721 4075);
DISPLAY 0.638298 (-1721 4075);
PAINT MONO (-1721 4075);
FORCEPROP 2 LAST PATH I155
J 2
(-2050 4150);
DISPLAY 1.021277 (-2050 4150);
DISPLAY INVISIBLE (-2050 4150);
FORCEPROP 1 LAST COMMENT_BODY TRUE
J 0
(-2045 3980);
DISPLAY 0.872340 (-2045 3980);
PAINT PEACH (-2045 3980);
DISPLAY INVISIBLE (-2045 3980);
FORCEPROP 1 LAST OFFPAGE TRUE
J 0
(-1675 3950);
DISPLAY 0.872340 (-1675 3950);
PAINT GREEN (-1675 3950);
DISPLAY INVISIBLE (-1675 3950);
FORCEPROP 2 LAST CDS_LIB standard
J 2
(-2000 4075);
DISPLAY INVISIBLE (-2000 4075);
FORCEADD OFFPAGE..4
(3050 1675);
FORCEPROP 2 LAST $XR0 32 
J 0
(3236 1675);
DISPLAY 0.638298 (3236 1675);
PAINT MONO (3236 1675);
FORCEPROP 2 LAST PATH I159
J 0
(3225 1750);
DISPLAY 1.021277 (3225 1750);
DISPLAY INVISIBLE (3225 1750);
FORCEPROP 1 LAST COMMENT_BODY TRUE
J 0
(3025 1575);
DISPLAY 0.872340 (3025 1575);
PAINT PEACH (3025 1575);
DISPLAY INVISIBLE (3025 1575);
FORCEPROP 1 LAST OFFPAGE TRUE
J 0
(3375 1550);
DISPLAY 0.872340 (3375 1550);
PAINT GREEN (3375 1550);
DISPLAY INVISIBLE (3375 1550);
FORCEPROP 2 LAST CDS_LIB standard
J 0
(3050 1675);
DISPLAY INVISIBLE (3050 1675);
FORCEADD Q_CAP..1
(3375 -725);
FORCEPROP 1 LAST PACK_TYPE 0402
J 0
(3425 -875);
DISPLAY 0.510638 (3425 -875);
PAINT SKYBLUE (3425 -875);
FORCEPROP 1 LAST PART_NUMBER CH4104K1B00
J 0
(3425 -925);
DISPLAY 0.510638 (3425 -925);
PAINT WHITE (3425 -925);
FORCEPROP 1 LAST VALUE 0.1UF
J 0
(3425 -675);
DISPLAY 0.510638 (3425 -675);
PAINT SKYBLUE (3425 -675);
FORCEPROP 1 LAST VOLTAGE 25V
J 0
(3425 -725);
DISPLAY 0.510638 (3425 -725);
PAINT SKYBLUE (3425 -725);
FORCEPROP 1 LAST TOLERANCE 10%
J 0
(3425 -775);
DISPLAY 0.510638 (3425 -775);
PAINT SKYBLUE (3425 -775);
FORCEPROP 1 LAST MATERIAL X7R
J 0
(3425 -825);
DISPLAY 0.510638 (3425 -825);
PAINT SKYBLUE (3425 -825);
FORCEPROP 1 LAST PATH I16
J 0
(3425 -575);
DISPLAY 0.978723 (3425 -575);
PAINT WHITE (3425 -575);
DISPLAY INVISIBLE (3425 -575);
FORCEPROP 2 LAST CDS_LIB pure_quanta
J 0
(3375 -725);
DISPLAY INVISIBLE (3375 -725);
FORCEPROP 1 LAST LOCATION C36
J 0
(3425 -625);
DISPLAY 0.702128 (3425 -625);
PAINT YELLOW (3425 -625);
FORCEPROP 1 LASTPIN (3375 -625) $PN 1
J 0
(3385 -645);
DISPLAY 0.808511 (3385 -645);
PAINT WHITE (3385 -645);
FORCEPROP 1 LASTPIN (3375 -825) $PN 2
J 0
(3385 -845);
DISPLAY 0.808511 (3385 -845);
PAINT WHITE (3385 -845);
FORCEPROP 2 LAST $SEC 1
J 0
(3425 -525);
DISPLAY 0.680851 (3425 -525);
PAINT MONO (3425 -525);
DISPLAY INVISIBLE (3425 -525);
FORCEPROP 0 LAST CDS_SEC 1
J 0
(3425 -525);
DISPLAY 0.680851 (3425 -525);
PAINT MONO (3425 -525);
DISPLAY INVISIBLE (3425 -525);
FORCEADD Q_RES..1
(3300 2625);
FORCEPROP 1 LAST VALUE 0
J 2
(3475 2625);
DISPLAY 0.510638 (3475 2625);
PAINT SKYBLUE (3475 2625);
FORCEPROP 1 LAST MATERIAL CHIP
J 0
(3500 2625);
DISPLAY 0.510638 (3500 2625);
PAINT SKYBLUE (3500 2625);
FORCEPROP 1 LAST PART_NUMBER CS00002JB13
J 0
(3250 2725);
DISPLAY 0.510638 (3250 2725);
PAINT WHITE (3250 2725);
DISPLAY INVISIBLE (3250 2725);
FORCEPROP 1 LAST PACK_TYPE 0402LF
J 0
(3550 2475);
DISPLAY 0.510638 (3550 2475);
PAINT SKYBLUE (3550 2475);
DISPLAY INVISIBLE (3550 2475);
FORCEPROP 1 LAST WATTAGE 1/16W
J 2
(3275 2475);
DISPLAY 0.510638 (3275 2475);
PAINT SKYBLUE (3275 2475);
DISPLAY INVISIBLE (3275 2475);
FORCEPROP 1 LAST PATH I168
J 0
(3250 2775);
DISPLAY 0.978723 (3250 2775);
PAINT WHITE (3250 2775);
DISPLAY INVISIBLE (3250 2775);
FORCEPROP 1 LAST TOLERANCE 5%
J 0
(3300 2525);
DISPLAY 0.510638 (3300 2525);
PAINT SKYBLUE (3300 2525);
DISPLAY INVISIBLE (3300 2525);
FORCEPROP 2 LAST CDS_LIB pure_quanta
J 0
(3300 2625);
DISPLAY INVISIBLE (3300 2625);
FORCEPROP 1 LAST LOCATION R528
J 0
(3100 2625);
DISPLAY 0.702128 (3100 2625);
PAINT YELLOW (3100 2625);
FORCEPROP 1 LASTPIN (3200 2625) $PN 1
J 0
(3212 2637);
DISPLAY 0.808511 (3212 2637);
PAINT WHITE (3212 2637);
FORCEPROP 1 LASTPIN (3400 2625) $PN 2
J 0
(3362 2637);
DISPLAY 0.808511 (3362 2637);
PAINT WHITE (3362 2637);
FORCEPROP 2 LAST $SEC 1
J 0
(3250 2825);
DISPLAY 0.680851 (3250 2825);
PAINT MONO (3250 2825);
DISPLAY INVISIBLE (3250 2825);
FORCEPROP 0 LAST CDS_SEC 1
J 0
(3250 2825);
DISPLAY 0.680851 (3250 2825);
PAINT MONO (3250 2825);
DISPLAY INVISIBLE (3250 2825);
FORCEADD Q_RES..1
(3300 2675);
FORCEPROP 1 LAST VALUE 0
J 2
(3475 2675);
DISPLAY 0.510638 (3475 2675);
PAINT SKYBLUE (3475 2675);
FORCEPROP 1 LAST MATERIAL CHIP
J 0
(3500 2675);
DISPLAY 0.510638 (3500 2675);
PAINT SKYBLUE (3500 2675);
FORCEPROP 2 LAST CDS_LIB pure_quanta
J 0
(3300 2675);
DISPLAY INVISIBLE (3300 2675);
FORCEPROP 1 LAST TOLERANCE 5%
J 0
(3300 2575);
DISPLAY 0.510638 (3300 2575);
PAINT SKYBLUE (3300 2575);
DISPLAY INVISIBLE (3300 2575);
FORCEPROP 1 LAST PATH I169
J 0
(3250 2825);
DISPLAY 0.978723 (3250 2825);
PAINT WHITE (3250 2825);
DISPLAY INVISIBLE (3250 2825);
FORCEPROP 1 LAST WATTAGE 1/16W
J 2
(3275 2525);
DISPLAY 0.510638 (3275 2525);
PAINT SKYBLUE (3275 2525);
DISPLAY INVISIBLE (3275 2525);
FORCEPROP 1 LAST PACK_TYPE 0402LF
J 0
(3550 2525);
DISPLAY 0.510638 (3550 2525);
PAINT SKYBLUE (3550 2525);
DISPLAY INVISIBLE (3550 2525);
FORCEPROP 1 LAST PART_NUMBER CS00002JB13
J 0
(3250 2775);
DISPLAY 0.510638 (3250 2775);
PAINT WHITE (3250 2775);
DISPLAY INVISIBLE (3250 2775);
FORCEPROP 1 LAST LOCATION R527
J 0
(3100 2675);
DISPLAY 0.702128 (3100 2675);
PAINT YELLOW (3100 2675);
FORCEPROP 1 LASTPIN (3200 2675) $PN 1
J 0
(3212 2687);
DISPLAY 0.808511 (3212 2687);
PAINT WHITE (3212 2687);
FORCEPROP 1 LASTPIN (3400 2675) $PN 2
J 0
(3362 2687);
DISPLAY 0.808511 (3362 2687);
PAINT WHITE (3362 2687);
FORCEPROP 2 LAST $SEC 1
J 0
(3250 2875);
DISPLAY 0.680851 (3250 2875);
PAINT MONO (3250 2875);
DISPLAY INVISIBLE (3250 2875);
FORCEPROP 0 LAST CDS_SEC 1
J 0
(3250 2875);
DISPLAY 0.680851 (3250 2875);
PAINT MONO (3250 2875);
DISPLAY INVISIBLE (3250 2875);
FORCEADD UNIVERSAL_GND..1
(5950 -1400);
FORCEPROP 3 LASTPIN (5950 -1350) SIG_NAME GND\g
J 0
(5960 -1340);
DISPLAY 0.659574 (5960 -1340);
PAINT MONO (5960 -1340);
DISPLAY INVISIBLE (5960 -1340);
FORCEPROP 1 LAST PATH I17
J 0
(6025 -1400);
DISPLAY 0.872340 (6025 -1400);
PAINT AQUA (6025 -1400);
DISPLAY INVISIBLE (6025 -1400);
FORCEPROP 1 LAST HDL_POWER GND
J 1
(5975 -1475);
DISPLAY 0.702128 (5975 -1475);
PAINT GREEN (5975 -1475);
DISPLAY INVISIBLE (5975 -1475);
FORCEPROP 2 LAST CDS_LIB logical_power
J 0
(5950 -1400);
DISPLAY INVISIBLE (5950 -1400);
FORCEADD OFFPAGE..3
(4500 2625);
FORCEPROP 2 LAST $XR0 10 
J 0
(4714 2625);
DISPLAY 0.638298 (4714 2625);
PAINT MONO (4714 2625);
FORCEPROP 2 LAST PATH I170
J 0
(4725 2675);
DISPLAY 1.021277 (4725 2675);
DISPLAY INVISIBLE (4725 2675);
FORCEPROP 1 LAST COMMENT_BODY TRUE
J 0
(4450 2525);
DISPLAY 0.872340 (4450 2525);
PAINT PEACH (4450 2525);
DISPLAY INVISIBLE (4450 2525);
FORCEPROP 1 LAST OFFPAGE TRUE
J 0
(4825 2500);
DISPLAY 0.872340 (4825 2500);
PAINT GREEN (4825 2500);
DISPLAY INVISIBLE (4825 2500);
FORCEPROP 2 LAST CDS_LIB standard
J 0
(4500 2625);
DISPLAY INVISIBLE (4500 2625);
FORCEADD OFFPAGE..3
(4500 2675);
FORCEPROP 2 LAST $XR0 10 
J 0
(4714 2675);
DISPLAY 0.638298 (4714 2675);
PAINT MONO (4714 2675);
FORCEPROP 2 LAST PATH I171
J 0
(4725 2725);
DISPLAY 1.021277 (4725 2725);
DISPLAY INVISIBLE (4725 2725);
FORCEPROP 1 LAST COMMENT_BODY TRUE
J 0
(4450 2575);
DISPLAY 0.872340 (4450 2575);
PAINT PEACH (4450 2575);
DISPLAY INVISIBLE (4450 2575);
FORCEPROP 1 LAST OFFPAGE TRUE
J 0
(4825 2550);
DISPLAY 0.872340 (4825 2550);
PAINT GREEN (4825 2550);
DISPLAY INVISIBLE (4825 2550);
FORCEPROP 2 LAST CDS_LIB standard
J 0
(4500 2675);
DISPLAY INVISIBLE (4500 2675);
FORCEADD Q_RES..1
(4425 4000);
FORCEPROP 1 LAST VALUE 4.7K
J 2
(4600 4000);
DISPLAY 0.510638 (4600 4000);
PAINT SKYBLUE (4600 4000);
FORCEPROP 1 LAST MATERIAL CHIP
J 0
(4625 4000);
DISPLAY 0.510638 (4625 4000);
PAINT SKYBLUE (4625 4000);
FORCEPROP 1 LAST TOLERANCE 1%
J 0
(4425 3900);
DISPLAY 0.510638 (4425 3900);
PAINT SKYBLUE (4425 3900);
DISPLAY INVISIBLE (4425 3900);
FORCEPROP 1 LAST WATTAGE 1/16W
J 2
(4400 3850);
DISPLAY 0.510638 (4400 3850);
PAINT SKYBLUE (4400 3850);
DISPLAY INVISIBLE (4400 3850);
FORCEPROP 1 LAST PACK_TYPE 0402LF
J 0
(4675 3850);
DISPLAY 0.510638 (4675 3850);
PAINT SKYBLUE (4675 3850);
DISPLAY INVISIBLE (4675 3850);
FORCEPROP 1 LAST PART_NUMBER CS24702FB06
J 0
(4375 4100);
DISPLAY 0.510638 (4375 4100);
PAINT WHITE (4375 4100);
DISPLAY INVISIBLE (4375 4100);
FORCEPROP 1 LAST PATH I174
J 0
(4375 4150);
DISPLAY 0.978723 (4375 4150);
PAINT WHITE (4375 4150);
DISPLAY INVISIBLE (4375 4150);
FORCEPROP 2 LAST CDS_LIB pure_quanta
J 0
(4425 4000);
DISPLAY INVISIBLE (4425 4000);
FORCEPROP 1 LAST LOCATION R717
J 2
(4350 4000);
DISPLAY 0.702128 (4350 4000);
PAINT YELLOW (4350 4000);
FORCEPROP 0 LAST $SEC 1
J 0
(4075 4050);
DISPLAY INVISIBLE (4075 4050);
FORCEPROP 0 LAST CDS_SEC 1
J 0
(4075 4050);
DISPLAY INVISIBLE (4075 4050);
FORCEPROP 1 LASTPIN (4325 4000) $PN 1
J 0
(4337 4012);
DISPLAY 0.808511 (4337 4012);
PAINT WHITE (4337 4012);
DISPLAY INVISIBLE (4337 4012);
FORCEPROP 1 LASTPIN (4525 4000) $PN 2
J 0
(4487 4012);
DISPLAY 0.808511 (4487 4012);
PAINT WHITE (4487 4012);
DISPLAY INVISIBLE (4487 4012);
FORCEADD VCCAUX15..1
(4225 4125);
FORCEPROP 3 LASTPIN (4225 4075) SIG_NAME P3V3_AUX\g
J 0
(4235 4085);
DISPLAY 0.659574 (4235 4085);
PAINT MONO (4235 4085);
DISPLAY INVISIBLE (4235 4085);
FORCEPROP 1 LAST HDL_POWER P3V3_AUX
J 1
(4350 4175);
DISPLAY 0.702128 (4350 4175);
PAINT GREEN (4350 4175);
FORCEPROP 1 LAST PATH I175
J 0
(4275 4150);
DISPLAY 0.872340 (4275 4150);
PAINT AQUA (4275 4150);
DISPLAY INVISIBLE (4275 4150);
FORCEPROP 2 LAST CDS_LIB logical_power
J 0
(4225 4125);
DISPLAY INVISIBLE (4225 4125);
FORCEADD OFFPAGE..2
(5575 4000);
FORCEPROP 2 LAST $XR0 15 
J 0
(5764 4000);
DISPLAY 0.638298 (5764 4000);
PAINT MONO (5764 4000);
FORCEPROP 2 LAST $XR1 34 
J 0
(5854 4000);
DISPLAY 0.638298 (5854 4000);
PAINT MONO (5854 4000);
FORCEPROP 1 LAST OFFPAGE TRUE
J 0
(5900 3875);
DISPLAY 0.872340 (5900 3875);
PAINT GREEN (5900 3875);
DISPLAY INVISIBLE (5900 3875);
FORCEPROP 1 LAST COMMENT_BODY TRUE
J 0
(5530 3905);
DISPLAY 0.872340 (5530 3905);
PAINT PEACH (5530 3905);
DISPLAY INVISIBLE (5530 3905);
FORCEPROP 2 LAST PATH I176
J 0
(5750 4075);
DISPLAY 1.021277 (5750 4075);
DISPLAY INVISIBLE (5750 4075);
FORCEPROP 2 LAST CDS_LIB standard
J 0
(5575 4000);
DISPLAY INVISIBLE (5575 4000);
FORCEADD MOSFET_N_GSD..1
(625 -700);
FORCEPROP 1 LAST PART_NUMBER BAM70020062
J 0
(726 -720);
DISPLAY 0.510638 (726 -720);
PAINT WHITE (726 -720);
FORCEPROP 2 LAST VALUE NX7002AK
J 0
(750 -600);
DISPLAY 0.510638 (750 -600);
PAINT SKYBLUE (750 -600);
FORCEPROP 2 LAST PART_TYPE SMLF
J 0
(750 -550);
DISPLAY 0.510638 (750 -550);
PAINT SKYBLUE (750 -550);
FORCEPROP 1 LAST MATERIAL IC
J 0
(726 -800);
DISPLAY 0.510638 (726 -800);
PAINT SKYBLUE (726 -800);
FORCEPROP 1 LAST PATH I179
J 0
(625 -700);
DISPLAY 0.723404 (625 -700);
PAINT GREEN (625 -700);
DISPLAY INVISIBLE (625 -700);
FORCEPROP 2 LAST CDS_LIB pure_quanta
J 0
(625 -700);
DISPLAY INVISIBLE (625 -700);
FORCEPROP 1 LAST NEEDS_NO_SIZE TRUE
J 0
(625 -700);
DISPLAY 0.468085 (625 -700);
PAINT GREEN (625 -700);
DISPLAY INVISIBLE (625 -700);
FORCEPROP 1 LAST CDS_LMAN_SYM_OUTLINE -100,100,100,-100
J 0
(625 -700);
DISPLAY 0.468085 (625 -700);
PAINT GREEN (625 -700);
DISPLAY INVISIBLE (625 -700);
FORCEPROP 1 LAST LOCATION Q11
J 0
(726 -655);
DISPLAY 0.702128 (726 -655);
PAINT YELLOW (726 -655);
FORCEPROP 0 LASTPIN (650 -550) $PN D
R 1
J 0
(640 -540);
DISPLAY 0.680851 (640 -540);
PAINT MONO (640 -540);
FORCEPROP 0 LASTPIN (450 -750) $PN G
J 2
(440 -740);
DISPLAY 0.680851 (440 -740);
PAINT MONO (440 -740);
FORCEPROP 0 LASTPIN (650 -850) $PN S
R 1
J 2
(640 -860);
DISPLAY 0.680851 (640 -860);
PAINT MONO (640 -860);
FORCEPROP 0 LAST $SEC 1
J 0
(750 -525);
DISPLAY 0.680851 (750 -525);
PAINT MONO (750 -525);
DISPLAY INVISIBLE (750 -525);
FORCEPROP 0 LAST CDS_SEC 1
J 0
(750 -525);
DISPLAY 0.680851 (750 -525);
DISPLAY INVISIBLE (750 -525);
FORCEADD UNIVERSAL_POWER..1
(3625 -300);
FORCEPROP 3 LASTPIN (3625 -350) SIG_NAME P3V3_P1V8_SD1VDD\g
J 0
(3635 -340);
DISPLAY 0.659574 (3635 -340);
PAINT MONO (3635 -340);
DISPLAY INVISIBLE (3635 -340);
FORCEPROP 1 LAST HDL_POWER P3V3_P1V8_SD1VDD
J 1
(3625 -250);
DISPLAY 0.702128 (3625 -250);
PAINT GREEN (3625 -250);
FORCEPROP 1 LAST PATH I18
J 0
(3675 -275);
DISPLAY 0.872340 (3675 -275);
PAINT AQUA (3675 -275);
DISPLAY INVISIBLE (3675 -275);
FORCEPROP 2 LAST CDS_LIB logical_power
J 0
(3625 -300);
DISPLAY INVISIBLE (3625 -300);
FORCEADD Q_CAP..1
(1100 -1250);
FORCEPROP 1 LAST PACK_TYPE 0402
J 0
(1150 -1450);
DISPLAY 0.510638 (1150 -1450);
PAINT SKYBLUE (1150 -1450);
FORCEPROP 1 LAST VALUE 100PF
J 0
(1150 -1200);
DISPLAY 0.510638 (1150 -1200);
PAINT SKYBLUE (1150 -1200);
FORCEPROP 1 LAST MATERIAL NPO
J 0
(1150 -1350);
DISPLAY 0.510638 (1150 -1350);
PAINT SKYBLUE (1150 -1350);
FORCEPROP 1 LAST PART_NUMBER CH11006JB00
J 0
(1150 -1400);
DISPLAY 0.510638 (1150 -1400);
PAINT WHITE (1150 -1400);
FORCEPROP 1 LAST TOLERANCE 5%
J 0
(1150 -1300);
DISPLAY 0.510638 (1150 -1300);
PAINT SKYBLUE (1150 -1300);
FORCEPROP 1 LAST VOLTAGE 50V
J 0
(1150 -1250);
DISPLAY 0.510638 (1150 -1250);
PAINT SKYBLUE (1150 -1250);
FORCEPROP 1 LAST PATH I180
J 0
(1150 -1100);
DISPLAY 0.978723 (1150 -1100);
PAINT WHITE (1150 -1100);
DISPLAY INVISIBLE (1150 -1100);
FORCEPROP 2 LAST CDS_LIB pure_quanta
J 0
(1100 -1250);
DISPLAY INVISIBLE (1100 -1250);
FORCEPROP 1 LAST LOCATION C275
J 0
(1150 -1150);
DISPLAY 0.702128 (1150 -1150);
PAINT YELLOW (1150 -1150);
FORCEPROP 0 LAST $SEC 1
J 0
(1150 -1100);
DISPLAY 0.680851 (1150 -1100);
PAINT MONO (1150 -1100);
DISPLAY INVISIBLE (1150 -1100);
FORCEPROP 0 LAST CDS_SEC 1
J 0
(1150 -1100);
DISPLAY 1.021277 (1150 -1100);
DISPLAY INVISIBLE (1150 -1100);
FORCEPROP 1 LASTPIN (1100 -1150) $PN 1
J 0
(1110 -1170);
DISPLAY 0.808511 (1110 -1170);
PAINT WHITE (1110 -1170);
DISPLAY INVISIBLE (1110 -1170);
FORCEPROP 1 LASTPIN (1100 -1350) $PN 2
J 0
(1110 -1370);
DISPLAY 0.808511 (1110 -1370);
PAINT WHITE (1110 -1370);
DISPLAY INVISIBLE (1110 -1370);
FORCEADD Q_RES..2
(650 -1250);
FORCEPROP 1 LAST PART_NUMBER CS41002FB09
J 0
(690 -1375);
DISPLAY 0.510638 (690 -1375);
PAINT WHITE (690 -1375);
FORCEPROP 1 LAST MATERIAL CHIP
J 0
(690 -1325);
DISPLAY 0.510638 (690 -1325);
PAINT SKYBLUE (690 -1325);
FORCEPROP 1 LAST WATTAGE 1/16W
J 0
(690 -1275);
DISPLAY 0.510638 (690 -1275);
PAINT SKYBLUE (690 -1275);
FORCEPROP 1 LAST VALUE 100K
J 0
(695 -1175);
DISPLAY 0.510638 (695 -1175);
PAINT SKYBLUE (695 -1175);
FORCEPROP 1 LAST PACK_TYPE 0402LF
J 0
(690 -1425);
DISPLAY 0.510638 (690 -1425);
PAINT SKYBLUE (690 -1425);
FORCEPROP 1 LAST TOLERANCE 1%
J 0
(695 -1225);
DISPLAY 0.510638 (695 -1225);
PAINT SKYBLUE (695 -1225);
FORCEPROP 1 LAST PATH I181
J 0
(700 -1075);
DISPLAY 0.978723 (700 -1075);
PAINT WHITE (700 -1075);
DISPLAY INVISIBLE (700 -1075);
FORCEPROP 2 LAST CDS_LIB pure_quanta
J 0
(650 -1250);
DISPLAY INVISIBLE (650 -1250);
FORCEPROP 1 LAST LOCATION R778
J 0
(695 -1125);
DISPLAY 0.702128 (695 -1125);
PAINT YELLOW (695 -1125);
FORCEPROP 0 LAST $SEC 1
J 0
(700 -1075);
DISPLAY 0.680851 (700 -1075);
PAINT MONO (700 -1075);
DISPLAY INVISIBLE (700 -1075);
FORCEPROP 0 LAST CDS_SEC 1
J 0
(700 -1075);
DISPLAY 1.021277 (700 -1075);
DISPLAY INVISIBLE (700 -1075);
FORCEPROP 1 LASTPIN (650 -1150) $PN 1
J 0
(655 -1188);
DISPLAY 0.808511 (655 -1188);
PAINT WHITE (655 -1188);
DISPLAY INVISIBLE (655 -1188);
FORCEPROP 1 LASTPIN (650 -1350) $PN 2
J 0
(655 -1340);
DISPLAY 0.808511 (655 -1340);
PAINT WHITE (655 -1340);
DISPLAY INVISIBLE (655 -1340);
FORCEADD Q_RES..1
(-400 -750);
FORCEPROP 1 LAST PART_NUMBER CS21002FB06
J 0
(-450 -650);
DISPLAY 0.510638 (-450 -650);
PAINT WHITE (-450 -650);
FORCEPROP 1 LAST WATTAGE 1/16W
J 2
(-425 -900);
DISPLAY 0.510638 (-425 -900);
PAINT SKYBLUE (-425 -900);
FORCEPROP 1 LAST MATERIAL CHIP
J 0
(-400 -900);
DISPLAY 0.510638 (-400 -900);
PAINT SKYBLUE (-400 -900);
FORCEPROP 1 LAST TOLERANCE 1%
J 0
(-400 -850);
DISPLAY 0.510638 (-400 -850);
PAINT SKYBLUE (-400 -850);
FORCEPROP 1 LAST VALUE 1K
J 2
(-425 -850);
DISPLAY 0.510638 (-425 -850);
PAINT SKYBLUE (-425 -850);
FORCEPROP 1 LAST PACK_TYPE 0402LF
J 0
(-150 -900);
DISPLAY 0.510638 (-150 -900);
PAINT SKYBLUE (-150 -900);
FORCEPROP 1 LAST PATH I183
J 0
(-450 -600);
DISPLAY 0.978723 (-450 -600);
PAINT WHITE (-450 -600);
DISPLAY INVISIBLE (-450 -600);
FORCEPROP 2 LAST CDS_LIB pure_quanta
J 0
(-400 -750);
DISPLAY INVISIBLE (-400 -750);
FORCEPROP 1 LAST LOCATION R775
J 0
(-450 -700);
DISPLAY 0.702128 (-450 -700);
PAINT YELLOW (-450 -700);
FORCEPROP 0 LAST $SEC 1
J 0
(-450 -625);
DISPLAY 0.680851 (-450 -625);
PAINT MONO (-450 -625);
DISPLAY INVISIBLE (-450 -625);
FORCEPROP 0 LAST CDS_SEC 1
J 0
(-450 -625);
DISPLAY 1.021277 (-450 -625);
DISPLAY INVISIBLE (-450 -625);
FORCEPROP 1 LASTPIN (-500 -750) $PN 1
J 0
(-488 -738);
DISPLAY 0.808511 (-488 -738);
PAINT WHITE (-488 -738);
DISPLAY INVISIBLE (-488 -738);
FORCEPROP 1 LASTPIN (-300 -750) $PN 2
J 0
(-338 -738);
DISPLAY 0.808511 (-338 -738);
PAINT WHITE (-338 -738);
DISPLAY INVISIBLE (-338 -738);
FORCEADD Q_RES..2
(250 -1100);
FORCEPROP 1 LAST PACK_TYPE 0402LF
J 0
(290 -1275);
DISPLAY 0.510638 (290 -1275);
PAINT SKYBLUE (290 -1275);
FORCEPROP 1 LAST PART_NUMBER CS34702FB01
J 0
(290 -1225);
DISPLAY 0.510638 (290 -1225);
PAINT WHITE (290 -1225);
FORCEPROP 1 LAST VALUE 47K
J 0
(295 -1025);
DISPLAY 0.510638 (295 -1025);
PAINT SKYBLUE (295 -1025);
FORCEPROP 1 LAST TOLERANCE 1%
J 0
(295 -1075);
DISPLAY 0.510638 (295 -1075);
PAINT SKYBLUE (295 -1075);
FORCEPROP 1 LAST WATTAGE 1/16W
J 0
(290 -1125);
DISPLAY 0.510638 (290 -1125);
PAINT SKYBLUE (290 -1125);
FORCEPROP 1 LAST MATERIAL CHIP
J 0
(290 -1175);
DISPLAY 0.510638 (290 -1175);
PAINT SKYBLUE (290 -1175);
FORCEPROP 1 LAST PATH I184
J 0
(300 -925);
DISPLAY 0.978723 (300 -925);
PAINT WHITE (300 -925);
DISPLAY INVISIBLE (300 -925);
FORCEPROP 2 LAST SEC_TYPE 0402LF
J 0
(300 -875);
DISPLAY 0.680851 (300 -875);
DISPLAY INVISIBLE (300 -875);
FORCEPROP 2 LAST CDS_LIB pure_quanta
J 0
(250 -1100);
DISPLAY INVISIBLE (250 -1100);
FORCEPROP 1 LAST LOCATION R776
J 0
(295 -975);
DISPLAY 0.702128 (295 -975);
PAINT YELLOW (295 -975);
FORCEPROP 1 LASTPIN (250 -1000) $PN 1
J 0
(255 -1038);
DISPLAY 0.808511 (255 -1038);
PAINT WHITE (255 -1038);
FORCEPROP 1 LASTPIN (250 -1200) $PN 2
J 0
(255 -1190);
DISPLAY 0.808511 (255 -1190);
PAINT WHITE (255 -1190);
FORCEPROP 2 LAST SEC 1
J 0
(300 -875);
DISPLAY 0.680851 (300 -875);
PAINT MONO (300 -875);
DISPLAY INVISIBLE (300 -875);
FORCEADD OFFPAGE..1
(200 -25);
FORCEPROP 2 LAST $XR0 10 
J 0
(-21 -25);
DISPLAY 0.638298 (-21 -25);
PAINT MONO (-21 -25);
FORCEPROP 2 LAST $XR1 50 
J 0
(-111 -25);
DISPLAY 0.638298 (-111 -25);
PAINT MONO (-111 -25);
FORCEPROP 2 LAST PATH I185
J 0
(250 50);
DISPLAY 1.021277 (250 50);
DISPLAY INVISIBLE (250 50);
FORCEPROP 1 LAST COMMENT_BODY TRUE
J 0
(325 -125);
DISPLAY 0.872340 (325 -125);
PAINT PEACH (325 -125);
DISPLAY INVISIBLE (325 -125);
FORCEPROP 1 LAST OFFPAGE TRUE
J 0
(525 -150);
DISPLAY 0.872340 (525 -150);
PAINT GREEN (525 -150);
DISPLAY INVISIBLE (525 -150);
FORCEPROP 2 LAST CDS_LIB standard
J 0
(200 -25);
DISPLAY INVISIBLE (200 -25);
FORCEADD OFFPAGE..1
(-1125 -750);
FORCEPROP 2 LAST $XR0 13 
J 0
(-1346 -750);
DISPLAY 0.638298 (-1346 -750);
PAINT MONO (-1346 -750);
FORCEPROP 2 LAST PATH I186
J 0
(-1075 -675);
DISPLAY 1.021277 (-1075 -675);
DISPLAY INVISIBLE (-1075 -675);
FORCEPROP 1 LAST COMMENT_BODY TRUE
J 0
(-1000 -850);
DISPLAY 0.872340 (-1000 -850);
PAINT PEACH (-1000 -850);
DISPLAY INVISIBLE (-1000 -850);
FORCEPROP 1 LAST OFFPAGE TRUE
J 0
(-800 -875);
DISPLAY 0.872340 (-800 -875);
PAINT GREEN (-800 -875);
DISPLAY INVISIBLE (-800 -875);
FORCEPROP 2 LAST CDS_LIB standard
J 0
(-1125 -750);
DISPLAY INVISIBLE (-1125 -750);
FORCEADD UNIVERSAL_GND..1
(650 -1550);
FORCEPROP 3 LASTPIN (650 -1500) SIG_NAME GND\g
J 0
(660 -1490);
DISPLAY 0.659574 (660 -1490);
PAINT MONO (660 -1490);
DISPLAY INVISIBLE (660 -1490);
FORCEPROP 1 LAST PATH I188
J 0
(725 -1550);
DISPLAY 0.872340 (725 -1550);
PAINT AQUA (725 -1550);
DISPLAY INVISIBLE (725 -1550);
FORCEPROP 1 LAST HDL_POWER GND
J 1
(634 -1584);
DISPLAY 0.702128 (634 -1584);
PAINT GREEN (634 -1584);
DISPLAY INVISIBLE (634 -1584);
FORCEPROP 2 LAST CDS_LIB logical_power
J 0
(650 -1550);
DISPLAY INVISIBLE (650 -1550);
FORCEADD UNIVERSAL_GND..1
(250 -1325);
FORCEPROP 3 LASTPIN (250 -1275) SIG_NAME GND\g
J 0
(260 -1265);
DISPLAY 0.659574 (260 -1265);
PAINT MONO (260 -1265);
DISPLAY INVISIBLE (260 -1265);
FORCEPROP 1 LAST PATH I189
J 0
(325 -1325);
DISPLAY 0.872340 (325 -1325);
PAINT AQUA (325 -1325);
DISPLAY INVISIBLE (325 -1325);
FORCEPROP 1 LAST HDL_POWER GND
J 1
(234 -1359);
DISPLAY 0.702128 (234 -1359);
PAINT GREEN (234 -1359);
DISPLAY INVISIBLE (234 -1359);
FORCEPROP 2 LAST CDS_LIB logical_power
J 0
(250 -1325);
DISPLAY INVISIBLE (250 -1325);
FORCEADD Q_RES..1
(5700 -1150);
FORCEPROP 1 LAST PART_NUMBER CS31002FB08
J 0
(5275 -1225);
DISPLAY 0.510638 (5275 -1225);
PAINT WHITE (5275 -1225);
FORCEPROP 1 LAST VALUE 10K
J 2
(5900 -1150);
DISPLAY 0.510638 (5900 -1150);
PAINT SKYBLUE (5900 -1150);
FORCEPROP 1 LAST MATERIAL EMPTY
J 0
(5825 -1200);
DISPLAY 0.510638 (5825 -1200);
PAINT RED (5825 -1200);
FORCEPROP 2 LAST CDS_LIB pure_quanta
J 0
(5700 -1150);
DISPLAY INVISIBLE (5700 -1150);
FORCEPROP 1 LAST PATH I19
J 0
(5650 -1000);
DISPLAY 0.978723 (5650 -1000);
PAINT WHITE (5650 -1000);
DISPLAY INVISIBLE (5650 -1000);
FORCEPROP 1 LAST TOLERANCE 1%
J 0
(5650 -1300);
DISPLAY 0.510638 (5650 -1300);
PAINT SKYBLUE (5650 -1300);
DISPLAY INVISIBLE (5650 -1300);
FORCEPROP 1 LAST WATTAGE 1/16W
J 2
(5400 -1300);
DISPLAY 0.510638 (5400 -1300);
PAINT SKYBLUE (5400 -1300);
DISPLAY INVISIBLE (5400 -1300);
FORCEPROP 1 LAST PACK_TYPE 0402LF
J 0
(5775 -1300);
DISPLAY 0.510638 (5775 -1300);
PAINT SKYBLUE (5775 -1300);
DISPLAY INVISIBLE (5775 -1300);
FORCEPROP 1 LAST LOCATION R209
J 0
(5525 -1150);
DISPLAY 0.702128 (5525 -1150);
PAINT YELLOW (5525 -1150);
FORCEPROP 1 LASTPIN (5600 -1150) $PN 1
J 0
(5612 -1138);
DISPLAY 0.808511 (5612 -1138);
PAINT WHITE (5612 -1138);
FORCEPROP 1 LASTPIN (5800 -1150) $PN 2
J 0
(5762 -1138);
DISPLAY 0.808511 (5762 -1138);
PAINT WHITE (5762 -1138);
FORCEPROP 0 LAST $SEC 1
J 0
(5525 -1100);
DISPLAY 0.680851 (5525 -1100);
PAINT MONO (5525 -1100);
DISPLAY INVISIBLE (5525 -1100);
FORCEPROP 0 LAST CDS_SEC 1
J 0
(5525 -1100);
DISPLAY 0.680851 (5525 -1100);
DISPLAY INVISIBLE (5525 -1100);
FORCEADD OFFPAGE..2
(1275 -975);
FORCEPROP 2 LAST $XR0 15 
J 0
(1464 -975);
DISPLAY 0.638298 (1464 -975);
PAINT MONO (1464 -975);
FORCEPROP 2 LAST PATH I190
J 0
(1450 -900);
DISPLAY 1.021277 (1450 -900);
DISPLAY INVISIBLE (1450 -900);
FORCEPROP 1 LAST COMMENT_BODY TRUE
J 0
(1230 -1070);
DISPLAY 0.872340 (1230 -1070);
PAINT PEACH (1230 -1070);
DISPLAY INVISIBLE (1230 -1070);
FORCEPROP 1 LAST OFFPAGE TRUE
J 0
(1600 -1100);
DISPLAY 0.872340 (1600 -1100);
PAINT GREEN (1600 -1100);
DISPLAY INVISIBLE (1600 -1100);
FORCEPROP 2 LAST CDS_LIB standard
J 0
(1275 -975);
DISPLAY INVISIBLE (1275 -975);
FORCEADD OFFPAGE..1
(-675 2675);
FORCEPROP 2 LAST $XR0 15 
J 0
(-896 2675);
DISPLAY 0.638298 (-896 2675);
PAINT MONO (-896 2675);
FORCEPROP 2 LAST PATH I191
J 0
(-625 2750);
DISPLAY 1.021277 (-625 2750);
DISPLAY INVISIBLE (-625 2750);
FORCEPROP 1 LAST COMMENT_BODY TRUE
J 0
(-550 2575);
DISPLAY 0.872340 (-550 2575);
PAINT PEACH (-550 2575);
DISPLAY INVISIBLE (-550 2575);
FORCEPROP 1 LAST OFFPAGE TRUE
J 0
(-350 2550);
DISPLAY 0.872340 (-350 2550);
PAINT GREEN (-350 2550);
DISPLAY INVISIBLE (-350 2550);
FORCEPROP 2 LAST CDS_LIB standard
J 0
(-675 2675);
DISPLAY INVISIBLE (-675 2675);
FORCEADD UNIVERSAL_POWER..1
(-2625 3675);
FORCEPROP 3 LASTPIN (-2625 3625) SIG_NAME P12V_AUX\g
J 0
(-2615 3635);
DISPLAY 0.659574 (-2615 3635);
PAINT MONO (-2615 3635);
DISPLAY INVISIBLE (-2615 3635);
FORCEPROP 1 LAST HDL_POWER P12V_AUX
J 1
(-2625 3725);
DISPLAY 0.702128 (-2625 3725);
PAINT GREEN (-2625 3725);
FORCEPROP 1 LAST PATH I194
J 0
(-2575 3700);
DISPLAY 0.872340 (-2575 3700);
PAINT AQUA (-2575 3700);
DISPLAY INVISIBLE (-2575 3700);
FORCEPROP 2 LAST CDS_LIB logical_power
J 0
(-2625 3675);
DISPLAY INVISIBLE (-2625 3675);
FORCEADD VCCAUX15..1
(-2625 2725);
FORCEPROP 3 LASTPIN (-2625 2675) SIG_NAME P5V_AUX\g
J 0
(-2615 2685);
DISPLAY 0.659574 (-2615 2685);
PAINT MONO (-2615 2685);
DISPLAY INVISIBLE (-2615 2685);
FORCEPROP 1 LAST HDL_POWER P5V_AUX
J 1
(-2625 2775);
DISPLAY 0.702128 (-2625 2775);
PAINT GREEN (-2625 2775);
FORCEPROP 1 LAST PATH I195
J 0
(-2575 2750);
DISPLAY 0.872340 (-2575 2750);
PAINT AQUA (-2575 2750);
DISPLAY INVISIBLE (-2575 2750);
FORCEPROP 2 LAST CDS_LIB logical_power
J 0
(-2625 2725);
DISPLAY INVISIBLE (-2625 2725);
FORCEADD VCCAUX15..1
(-2625 600);
FORCEPROP 3 LASTPIN (-2625 550) SIG_NAME P2V5_AUX\g
J 0
(-2615 560);
DISPLAY 0.659574 (-2615 560);
PAINT MONO (-2615 560);
DISPLAY INVISIBLE (-2615 560);
FORCEPROP 1 LAST HDL_POWER P2V5_AUX
J 1
(-2625 650);
DISPLAY 0.702128 (-2625 650);
PAINT GREEN (-2625 650);
FORCEPROP 1 LAST PATH I196
J 0
(-2575 625);
DISPLAY 0.872340 (-2575 625);
PAINT AQUA (-2575 625);
DISPLAY INVISIBLE (-2575 625);
FORCEPROP 2 LAST CDS_LIB logical_power
J 0
(-2625 600);
DISPLAY INVISIBLE (-2625 600);
FORCEADD VCCAUX15..1
(-1650 1625);
FORCEPROP 3 LASTPIN (-1650 1575) SIG_NAME P1V2_AUX\g
J 0
(-1640 1585);
DISPLAY 0.659574 (-1640 1585);
PAINT MONO (-1640 1585);
DISPLAY INVISIBLE (-1640 1585);
FORCEPROP 1 LAST HDL_POWER P1V2_AUX
J 1
(-1650 1675);
DISPLAY 0.702128 (-1650 1675);
PAINT GREEN (-1650 1675);
FORCEPROP 1 LAST PATH I197
J 0
(-1600 1650);
DISPLAY 0.872340 (-1600 1650);
PAINT AQUA (-1600 1650);
DISPLAY INVISIBLE (-1600 1650);
FORCEPROP 2 LAST CDS_LIB logical_power
J 0
(-1650 1625);
DISPLAY INVISIBLE (-1650 1625);
FORCEADD VCCAUX15..1
(-1625 525);
FORCEPROP 3 LASTPIN (-1625 475) SIG_NAME P1V0_AUX\g
J 0
(-1615 485);
DISPLAY 0.659574 (-1615 485);
PAINT MONO (-1615 485);
DISPLAY INVISIBLE (-1615 485);
FORCEPROP 1 LAST HDL_POWER P1V0_AUX
J 1
(-1625 575);
DISPLAY 0.702128 (-1625 575);
PAINT GREEN (-1625 575);
FORCEPROP 2 LAST CDS_LIB logical_power
J 0
(-1625 525);
DISPLAY INVISIBLE (-1625 525);
FORCEPROP 1 LAST PATH I199
J 0
(-1575 550);
DISPLAY 0.872340 (-1575 550);
PAINT AQUA (-1575 550);
DISPLAY INVISIBLE (-1575 550);
FORCEADD Q_RES..1
(2425 -850);
FORCEPROP 1 LAST VALUE 0
J 2
(2625 -850);
DISPLAY 0.510638 (2625 -850);
PAINT SKYBLUE (2625 -850);
FORCEPROP 1 LAST MATERIAL EMPTY
J 0
(2700 -850);
DISPLAY 0.510638 (2700 -850);
PAINT RED (2700 -850);
FORCEPROP 1 LAST PART_NUMBER CS00002JB13
J 0
(2425 -675);
DISPLAY 0.510638 (2425 -675);
PAINT WHITE (2425 -675);
DISPLAY INVISIBLE (2425 -675);
FORCEPROP 1 LAST PACK_TYPE 0402LF
J 0
(2625 -750);
DISPLAY 0.510638 (2625 -750);
PAINT SKYBLUE (2625 -750);
DISPLAY INVISIBLE (2625 -750);
FORCEPROP 1 LAST WATTAGE 1/16W
J 2
(2600 -750);
DISPLAY 0.510638 (2600 -750);
PAINT SKYBLUE (2600 -750);
DISPLAY INVISIBLE (2600 -750);
FORCEPROP 1 LAST PATH I2
J 0
(2375 -700);
DISPLAY 0.978723 (2375 -700);
PAINT WHITE (2375 -700);
DISPLAY INVISIBLE (2375 -700);
FORCEPROP 1 LAST TOLERANCE 5%
J 0
(2925 -750);
DISPLAY 0.510638 (2925 -750);
PAINT SKYBLUE (2925 -750);
DISPLAY INVISIBLE (2925 -750);
FORCEPROP 2 LAST CDS_LIB pure_quanta
J 0
(2425 -850);
DISPLAY INVISIBLE (2425 -850);
FORCEPROP 1 LAST LOCATION R208
J 0
(2175 -850);
DISPLAY 0.702128 (2175 -850);
PAINT YELLOW (2175 -850);
FORCEPROP 1 LASTPIN (2325 -850) $PN 1
J 0
(2337 -838);
DISPLAY 0.808511 (2337 -838);
PAINT WHITE (2337 -838);
FORCEPROP 1 LASTPIN (2525 -850) $PN 2
J 0
(2487 -838);
DISPLAY 0.808511 (2487 -838);
PAINT WHITE (2487 -838);
FORCEPROP 2 LAST $SEC 1
J 0
(2375 -650);
DISPLAY 0.680851 (2375 -650);
PAINT MONO (2375 -650);
DISPLAY INVISIBLE (2375 -650);
FORCEPROP 0 LAST CDS_SEC 1
J 0
(2375 -650);
DISPLAY 0.680851 (2375 -650);
PAINT MONO (2375 -650);
DISPLAY INVISIBLE (2375 -650);
FORCEADD VCCAUX15..1
(-2625 -500);
FORCEPROP 3 LASTPIN (-2625 -550) SIG_NAME P1V8_AUX\g
J 0
(-2615 -540);
DISPLAY 0.659574 (-2615 -540);
PAINT MONO (-2615 -540);
DISPLAY INVISIBLE (-2615 -540);
FORCEPROP 1 LAST HDL_POWER P1V8_AUX
J 1
(-2625 -450);
DISPLAY 0.702128 (-2625 -450);
PAINT GREEN (-2625 -450);
FORCEPROP 1 LAST PATH I200
J 0
(-2575 -475);
DISPLAY 0.872340 (-2575 -475);
PAINT AQUA (-2575 -475);
DISPLAY INVISIBLE (-2575 -475);
FORCEPROP 2 LAST CDS_LIB logical_power
J 0
(-2625 -500);
DISPLAY INVISIBLE (-2625 -500);
FORCEADD Q_CAP..1
(-2425 3100);
FORCEPROP 1 LAST TOLERANCE 10%
J 0
(-2375 3050);
DISPLAY 0.510638 (-2375 3050);
PAINT SKYBLUE (-2375 3050);
FORCEPROP 1 LAST PACK_TYPE 0402
J 0
(-2375 2950);
DISPLAY 0.510638 (-2375 2950);
PAINT SKYBLUE (-2375 2950);
FORCEPROP 1 LAST MATERIAL X7R
J 0
(-2375 3000);
DISPLAY 0.510638 (-2375 3000);
PAINT SKYBLUE (-2375 3000);
FORCEPROP 1 LAST PART_NUMBER CH4104K1B00
J 0
(-2375 2900);
DISPLAY 0.510638 (-2375 2900);
PAINT WHITE (-2375 2900);
FORCEPROP 1 LAST VOLTAGE 25V
J 0
(-2375 3100);
DISPLAY 0.510638 (-2375 3100);
PAINT SKYBLUE (-2375 3100);
FORCEPROP 1 LAST VALUE 0.1UF
J 0
(-2375 3150);
DISPLAY 0.510638 (-2375 3150);
PAINT SKYBLUE (-2375 3150);
FORCEPROP 1 LAST PATH I201
J 0
(-2375 3250);
DISPLAY 0.978723 (-2375 3250);
PAINT WHITE (-2375 3250);
DISPLAY INVISIBLE (-2375 3250);
FORCEPROP 2 LAST CDS_LIB pure_quanta
J 0
(-2425 3100);
DISPLAY INVISIBLE (-2425 3100);
FORCEPROP 1 LAST LOCATION C290
J 0
(-2375 3200);
DISPLAY 0.702128 (-2375 3200);
PAINT YELLOW (-2375 3200);
FORCEPROP 1 LASTPIN (-2425 3200) $PN 1
J 0
(-2415 3180);
DISPLAY 0.808511 (-2415 3180);
PAINT WHITE (-2415 3180);
FORCEPROP 1 LASTPIN (-2425 3000) $PN 2
J 0
(-2415 2980);
DISPLAY 0.808511 (-2415 2980);
PAINT WHITE (-2415 2980);
FORCEPROP 2 LAST $SEC 1
J 0
(-2375 3300);
DISPLAY 0.680851 (-2375 3300);
PAINT MONO (-2375 3300);
DISPLAY INVISIBLE (-2375 3300);
FORCEPROP 0 LAST CDS_SEC 1
J 0
(-2375 3300);
DISPLAY 0.680851 (-2375 3300);
PAINT MONO (-2375 3300);
DISPLAY INVISIBLE (-2375 3300);
FORCEADD Q_RES..2
R 2
(-2625 3475);
FORCEPROP 1 LAST PART_NUMBER CS31582FB02
J 2
(-2665 3350);
DISPLAY 0.510638 (-2665 3350);
PAINT WHITE (-2665 3350);
FORCEPROP 1 LAST PACK_TYPE 0402LF
J 2
(-2665 3300);
DISPLAY 0.510638 (-2665 3300);
PAINT SKYBLUE (-2665 3300);
FORCEPROP 1 LAST WATTAGE 1/16W
J 2
(-2665 3450);
DISPLAY 0.510638 (-2665 3450);
PAINT SKYBLUE (-2665 3450);
FORCEPROP 1 LAST TOLERANCE 1%
J 2
(-2670 3500);
DISPLAY 0.510638 (-2670 3500);
PAINT SKYBLUE (-2670 3500);
FORCEPROP 1 LAST VALUE 15.8K
J 2
(-2670 3550);
DISPLAY 0.510638 (-2670 3550);
PAINT SKYBLUE (-2670 3550);
FORCEPROP 1 LAST MATERIAL CHIP
J 2
(-2665 3400);
DISPLAY 0.510638 (-2665 3400);
PAINT SKYBLUE (-2665 3400);
FORCEPROP 1 LAST PATH I202
J 2
(-2675 3650);
DISPLAY 0.978723 (-2675 3650);
PAINT WHITE (-2675 3650);
DISPLAY INVISIBLE (-2675 3650);
FORCEPROP 2 LAST CDS_LIB pure_quanta
J 2
(-2625 3475);
DISPLAY INVISIBLE (-2625 3475);
FORCEPROP 1 LAST LOCATION R785
J 2
(-2670 3600);
DISPLAY 0.702128 (-2670 3600);
PAINT YELLOW (-2670 3600);
FORCEPROP 0 LAST $SEC 1
J 0
(-2650 3650);
DISPLAY 0.680851 (-2650 3650);
PAINT MONO (-2650 3650);
DISPLAY INVISIBLE (-2650 3650);
FORCEPROP 0 LAST CDS_SEC 1
J 0
(-2650 3650);
DISPLAY 1.021277 (-2650 3650);
DISPLAY INVISIBLE (-2650 3650);
FORCEPROP 1 LASTPIN (-2625 3575) $PN 1
J 2
(-2630 3537);
DISPLAY 0.808511 (-2630 3537);
PAINT WHITE (-2630 3537);
DISPLAY INVISIBLE (-2630 3537);
FORCEPROP 1 LASTPIN (-2625 3375) $PN 2
J 2
(-2630 3385);
DISPLAY 0.808511 (-2630 3385);
PAINT WHITE (-2630 3385);
DISPLAY INVISIBLE (-2630 3385);
FORCEADD Q_RES..2
R 2
(-2625 3100);
FORCEPROP 1 LAST PART_NUMBER CS22002FB07
J 2
(-2665 2975);
DISPLAY 0.510638 (-2665 2975);
PAINT WHITE (-2665 2975);
FORCEPROP 1 LAST PACK_TYPE 0402LF
J 2
(-2665 2925);
DISPLAY 0.510638 (-2665 2925);
PAINT SKYBLUE (-2665 2925);
FORCEPROP 1 LAST MATERIAL CHIP
J 2
(-2665 3025);
DISPLAY 0.510638 (-2665 3025);
PAINT SKYBLUE (-2665 3025);
FORCEPROP 1 LAST VALUE 2K
J 2
(-2670 3175);
DISPLAY 0.510638 (-2670 3175);
PAINT SKYBLUE (-2670 3175);
FORCEPROP 1 LAST WATTAGE 1/16W
J 2
(-2665 3075);
DISPLAY 0.510638 (-2665 3075);
PAINT SKYBLUE (-2665 3075);
FORCEPROP 1 LAST TOLERANCE 1%
J 2
(-2670 3125);
DISPLAY 0.510638 (-2670 3125);
PAINT SKYBLUE (-2670 3125);
FORCEPROP 1 LAST PATH I203
J 2
(-2675 3275);
DISPLAY 0.978723 (-2675 3275);
PAINT WHITE (-2675 3275);
DISPLAY INVISIBLE (-2675 3275);
FORCEPROP 2 LAST CDS_LIB pure_quanta
J 2
(-2625 3100);
DISPLAY INVISIBLE (-2625 3100);
FORCEPROP 1 LAST LOCATION R786
J 2
(-2670 3225);
DISPLAY 0.702128 (-2670 3225);
PAINT YELLOW (-2670 3225);
FORCEPROP 0 LAST $SEC 1
J 0
(-2650 3275);
DISPLAY 0.680851 (-2650 3275);
PAINT MONO (-2650 3275);
DISPLAY INVISIBLE (-2650 3275);
FORCEPROP 0 LAST CDS_SEC 1
J 0
(-2650 3275);
DISPLAY 1.021277 (-2650 3275);
DISPLAY INVISIBLE (-2650 3275);
FORCEPROP 1 LASTPIN (-2625 3200) $PN 1
J 2
(-2630 3162);
DISPLAY 0.808511 (-2630 3162);
PAINT WHITE (-2630 3162);
DISPLAY INVISIBLE (-2630 3162);
FORCEPROP 1 LASTPIN (-2625 3000) $PN 2
J 2
(-2630 3010);
DISPLAY 0.808511 (-2630 3010);
PAINT WHITE (-2630 3010);
DISPLAY INVISIBLE (-2630 3010);
FORCEADD UNIVERSAL_GND..1
(-2625 2825);
FORCEPROP 3 LASTPIN (-2625 2875) SIG_NAME GND\g
J 0
(-2615 2885);
DISPLAY 0.659574 (-2615 2885);
PAINT MONO (-2615 2885);
DISPLAY INVISIBLE (-2615 2885);
FORCEPROP 1 LAST PATH I204
J 0
(-2550 2825);
DISPLAY 0.872340 (-2550 2825);
PAINT AQUA (-2550 2825);
DISPLAY INVISIBLE (-2550 2825);
FORCEPROP 1 LAST HDL_POWER GND
J 1
(-2641 2791);
DISPLAY 0.702128 (-2641 2791);
PAINT GREEN (-2641 2791);
DISPLAY INVISIBLE (-2641 2791);
FORCEPROP 2 LAST CDS_LIB logical_power
J 0
(-2625 2825);
DISPLAY INVISIBLE (-2625 2825);
FORCEADD OFFPAGE..2
(-2075 3250);
FORCEPROP 2 LAST $XR0 15 
J 0
(-1886 3250);
DISPLAY 0.638298 (-1886 3250);
PAINT MONO (-1886 3250);
FORCEPROP 2 LAST PATH I205
J 0
(-1775 3300);
DISPLAY 1.021277 (-1775 3300);
DISPLAY INVISIBLE (-1775 3300);
FORCEPROP 1 LAST COMMENT_BODY TRUE
J 0
(-2120 3155);
DISPLAY 0.872340 (-2120 3155);
PAINT PEACH (-2120 3155);
DISPLAY INVISIBLE (-2120 3155);
FORCEPROP 1 LAST OFFPAGE TRUE
J 0
(-1750 3125);
DISPLAY 0.872340 (-1750 3125);
PAINT GREEN (-1750 3125);
DISPLAY INVISIBLE (-1750 3125);
FORCEPROP 2 LAST CDS_LIB standard
J 2
(-2075 3250);
DISPLAY INVISIBLE (-2075 3250);
FORCEADD OFFPAGE..1
(-675 3025);
FORCEPROP 2 LAST $XR0 15 
J 0
(-896 3025);
DISPLAY 0.638298 (-896 3025);
PAINT MONO (-896 3025);
FORCEPROP 2 LAST PATH I206
J 0
(-925 3075);
DISPLAY 1.021277 (-925 3075);
DISPLAY INVISIBLE (-925 3075);
FORCEPROP 1 LAST COMMENT_BODY TRUE
J 0
(-550 2925);
DISPLAY 0.872340 (-550 2925);
PAINT PEACH (-550 2925);
DISPLAY INVISIBLE (-550 2925);
FORCEPROP 1 LAST OFFPAGE TRUE
J 0
(-350 2900);
DISPLAY 0.872340 (-350 2900);
PAINT GREEN (-350 2900);
DISPLAY INVISIBLE (-350 2900);
FORCEPROP 2 LAST CDS_LIB standard
J 0
(-675 3025);
DISPLAY INVISIBLE (-675 3025);
FORCEADD Q_CAP..1
(-2425 2150);
FORCEPROP 1 LAST PART_NUMBER CH4104K1B00
J 0
(-2375 1950);
DISPLAY 0.510638 (-2375 1950);
PAINT WHITE (-2375 1950);
FORCEPROP 1 LAST PACK_TYPE 0402
J 0
(-2375 2000);
DISPLAY 0.510638 (-2375 2000);
PAINT SKYBLUE (-2375 2000);
FORCEPROP 1 LAST TOLERANCE 10%
J 0
(-2375 2100);
DISPLAY 0.510638 (-2375 2100);
PAINT SKYBLUE (-2375 2100);
FORCEPROP 1 LAST VALUE 0.1UF
J 0
(-2375 2200);
DISPLAY 0.510638 (-2375 2200);
PAINT SKYBLUE (-2375 2200);
FORCEPROP 1 LAST MATERIAL X7R
J 0
(-2375 2050);
DISPLAY 0.510638 (-2375 2050);
PAINT SKYBLUE (-2375 2050);
FORCEPROP 1 LAST VOLTAGE 25V
J 0
(-2375 2150);
DISPLAY 0.510638 (-2375 2150);
PAINT SKYBLUE (-2375 2150);
FORCEPROP 1 LAST PATH I207
J 0
(-2375 2300);
DISPLAY 0.978723 (-2375 2300);
PAINT WHITE (-2375 2300);
DISPLAY INVISIBLE (-2375 2300);
FORCEPROP 2 LAST CDS_LIB pure_quanta
J 0
(-2425 2150);
DISPLAY INVISIBLE (-2425 2150);
FORCEPROP 1 LAST LOCATION C295
J 0
(-2375 2250);
DISPLAY 0.702128 (-2375 2250);
PAINT YELLOW (-2375 2250);
FORCEPROP 1 LASTPIN (-2425 2250) $PN 1
J 0
(-2415 2230);
DISPLAY 0.808511 (-2415 2230);
PAINT WHITE (-2415 2230);
FORCEPROP 1 LASTPIN (-2425 2050) $PN 2
J 0
(-2415 2030);
DISPLAY 0.808511 (-2415 2030);
PAINT WHITE (-2415 2030);
FORCEPROP 2 LAST $SEC 1
J 0
(-2375 2350);
DISPLAY 0.680851 (-2375 2350);
PAINT MONO (-2375 2350);
DISPLAY INVISIBLE (-2375 2350);
FORCEPROP 0 LAST CDS_SEC 1
J 0
(-2375 2350);
DISPLAY 0.680851 (-2375 2350);
PAINT MONO (-2375 2350);
DISPLAY INVISIBLE (-2375 2350);
FORCEADD Q_RES..2
(-500 625);
FORCEPROP 1 LAST MATERIAL CHIP
J 0
(-460 550);
DISPLAY 0.510638 (-460 550);
PAINT SKYBLUE (-460 550);
FORCEPROP 1 LAST VALUE 4.7K
J 0
(-455 700);
DISPLAY 0.510638 (-455 700);
PAINT SKYBLUE (-455 700);
FORCEPROP 1 LAST TOLERANCE 1%
J 0
(-455 650);
DISPLAY 0.510638 (-455 650);
PAINT SKYBLUE (-455 650);
FORCEPROP 1 LAST WATTAGE 1/16W
J 0
(-460 600);
DISPLAY 0.510638 (-460 600);
PAINT SKYBLUE (-460 600);
FORCEPROP 1 LAST PACK_TYPE 0402LF
J 0
(-450 500);
DISPLAY 0.510638 (-450 500);
PAINT SKYBLUE (-450 500);
FORCEPROP 1 LAST PART_NUMBER CS24702FB06
J 0
(-460 500);
DISPLAY 0.510638 (-460 500);
PAINT WHITE (-460 500);
DISPLAY INVISIBLE (-460 500);
FORCEPROP 1 LAST PATH I21
J 0
(-450 800);
DISPLAY 0.978723 (-450 800);
PAINT WHITE (-450 800);
DISPLAY INVISIBLE (-450 800);
FORCEPROP 2 LAST CDS_LIB pure_quanta
J 0
(-500 625);
DISPLAY INVISIBLE (-500 625);
FORCEPROP 1 LAST LOCATION R212
J 0
(-455 750);
DISPLAY 0.702128 (-455 750);
PAINT YELLOW (-455 750);
FORCEPROP 1 LASTPIN (-500 725) $PN 1
J 0
(-495 687);
DISPLAY 0.808511 (-495 687);
PAINT WHITE (-495 687);
FORCEPROP 1 LASTPIN (-500 525) $PN 2
J 0
(-495 535);
DISPLAY 0.808511 (-495 535);
PAINT WHITE (-495 535);
FORCEPROP 2 LAST $SEC 1
J 0
(-450 850);
DISPLAY 0.680851 (-450 850);
PAINT MONO (-450 850);
DISPLAY INVISIBLE (-450 850);
FORCEPROP 0 LAST CDS_SEC 1
J 0
(-450 850);
DISPLAY 0.680851 (-450 850);
PAINT MONO (-450 850);
DISPLAY INVISIBLE (-450 850);
FORCEADD OFFPAGE..2
(-2075 2300);
FORCEPROP 2 LAST $XR0 15 
J 0
(-1886 2300);
DISPLAY 0.638298 (-1886 2300);
PAINT MONO (-1886 2300);
FORCEPROP 2 LAST PATH I210
J 0
(-1775 2350);
DISPLAY 1.021277 (-1775 2350);
DISPLAY INVISIBLE (-1775 2350);
FORCEPROP 1 LAST COMMENT_BODY TRUE
J 0
(-2120 2205);
DISPLAY 0.872340 (-2120 2205);
PAINT PEACH (-2120 2205);
DISPLAY INVISIBLE (-2120 2205);
FORCEPROP 1 LAST OFFPAGE TRUE
J 0
(-1750 2175);
DISPLAY 0.872340 (-1750 2175);
PAINT GREEN (-1750 2175);
DISPLAY INVISIBLE (-1750 2175);
FORCEPROP 2 LAST CDS_LIB standard
J 2
(-2075 2300);
DISPLAY INVISIBLE (-2075 2300);
FORCEADD Q_RES..2
R 2
(-2625 2150);
FORCEPROP 1 LAST PART_NUMBER CS22002FB07
J 2
(-2665 2025);
DISPLAY 0.510638 (-2665 2025);
PAINT WHITE (-2665 2025);
FORCEPROP 1 LAST PACK_TYPE 0402LF
J 2
(-2665 1975);
DISPLAY 0.510638 (-2665 1975);
PAINT SKYBLUE (-2665 1975);
FORCEPROP 1 LAST VALUE 2K
J 2
(-2670 2225);
DISPLAY 0.510638 (-2670 2225);
PAINT SKYBLUE (-2670 2225);
FORCEPROP 1 LAST TOLERANCE 1%
J 2
(-2670 2175);
DISPLAY 0.510638 (-2670 2175);
PAINT SKYBLUE (-2670 2175);
FORCEPROP 1 LAST WATTAGE 1/16W
J 2
(-2665 2125);
DISPLAY 0.510638 (-2665 2125);
PAINT SKYBLUE (-2665 2125);
FORCEPROP 1 LAST MATERIAL CHIP
J 2
(-2665 2075);
DISPLAY 0.510638 (-2665 2075);
PAINT SKYBLUE (-2665 2075);
FORCEPROP 1 LAST PATH I211
J 2
(-2675 2325);
DISPLAY 0.978723 (-2675 2325);
PAINT WHITE (-2675 2325);
DISPLAY INVISIBLE (-2675 2325);
FORCEPROP 2 LAST CDS_LIB pure_quanta
J 2
(-2625 2150);
DISPLAY INVISIBLE (-2625 2150);
FORCEPROP 1 LAST LOCATION R788
J 2
(-2670 2275);
DISPLAY 0.702128 (-2670 2275);
PAINT YELLOW (-2670 2275);
FORCEPROP 0 LAST $SEC 1
J 0
(-2650 2325);
DISPLAY 0.680851 (-2650 2325);
PAINT MONO (-2650 2325);
DISPLAY INVISIBLE (-2650 2325);
FORCEPROP 0 LAST CDS_SEC 1
J 0
(-2650 2325);
DISPLAY 1.021277 (-2650 2325);
DISPLAY INVISIBLE (-2650 2325);
FORCEPROP 1 LASTPIN (-2625 2250) $PN 1
J 2
(-2630 2212);
DISPLAY 0.808511 (-2630 2212);
PAINT WHITE (-2630 2212);
DISPLAY INVISIBLE (-2630 2212);
FORCEPROP 1 LASTPIN (-2625 2050) $PN 2
J 2
(-2630 2060);
DISPLAY 0.808511 (-2630 2060);
PAINT WHITE (-2630 2060);
DISPLAY INVISIBLE (-2630 2060);
FORCEADD UNIVERSAL_GND..1
(-2625 1875);
FORCEPROP 3 LASTPIN (-2625 1925) SIG_NAME GND\g
J 0
(-2615 1935);
DISPLAY 0.659574 (-2615 1935);
PAINT MONO (-2615 1935);
DISPLAY INVISIBLE (-2615 1935);
FORCEPROP 1 LAST PATH I212
J 0
(-2550 1875);
DISPLAY 0.872340 (-2550 1875);
PAINT AQUA (-2550 1875);
DISPLAY INVISIBLE (-2550 1875);
FORCEPROP 1 LAST HDL_POWER GND
J 1
(-2641 1841);
DISPLAY 0.702128 (-2641 1841);
PAINT GREEN (-2641 1841);
DISPLAY INVISIBLE (-2641 1841);
FORCEPROP 2 LAST CDS_LIB logical_power
J 0
(-2625 1875);
DISPLAY INVISIBLE (-2625 1875);
FORCEADD OFFPAGE..1
(-675 2975);
FORCEPROP 2 LAST $XR0 15 
J 0
(-896 2975);
DISPLAY 0.638298 (-896 2975);
PAINT MONO (-896 2975);
FORCEPROP 2 LAST PATH I213
J 0
(-925 3025);
DISPLAY 1.021277 (-925 3025);
DISPLAY INVISIBLE (-925 3025);
FORCEPROP 1 LAST COMMENT_BODY TRUE
J 0
(-550 2875);
DISPLAY 0.872340 (-550 2875);
PAINT PEACH (-550 2875);
DISPLAY INVISIBLE (-550 2875);
FORCEPROP 1 LAST OFFPAGE TRUE
J 0
(-350 2850);
DISPLAY 0.872340 (-350 2850);
PAINT GREEN (-350 2850);
DISPLAY INVISIBLE (-350 2850);
FORCEPROP 2 LAST CDS_LIB standard
J 0
(-675 2975);
DISPLAY INVISIBLE (-675 2975);
FORCEADD Q_CAP..1
(-2425 1150);
FORCEPROP 1 LAST TOLERANCE 10%
J 0
(-2375 1100);
DISPLAY 0.510638 (-2375 1100);
PAINT SKYBLUE (-2375 1100);
FORCEPROP 1 LAST VALUE 0.1UF
J 0
(-2375 1200);
DISPLAY 0.510638 (-2375 1200);
PAINT SKYBLUE (-2375 1200);
FORCEPROP 1 LAST MATERIAL X7R
J 0
(-2375 1050);
DISPLAY 0.510638 (-2375 1050);
PAINT SKYBLUE (-2375 1050);
FORCEPROP 1 LAST VOLTAGE 25V
J 0
(-2375 1150);
DISPLAY 0.510638 (-2375 1150);
PAINT SKYBLUE (-2375 1150);
FORCEPROP 1 LAST PACK_TYPE 0402
J 0
(-2375 1000);
DISPLAY 0.510638 (-2375 1000);
PAINT SKYBLUE (-2375 1000);
FORCEPROP 1 LAST PART_NUMBER CH4104K1B00
J 0
(-2375 950);
DISPLAY 0.510638 (-2375 950);
PAINT WHITE (-2375 950);
FORCEPROP 1 LAST PATH I215
J 0
(-2375 1300);
DISPLAY 0.978723 (-2375 1300);
PAINT WHITE (-2375 1300);
DISPLAY INVISIBLE (-2375 1300);
FORCEPROP 2 LAST CDS_LIB pure_quanta
J 0
(-2425 1150);
DISPLAY INVISIBLE (-2425 1150);
FORCEPROP 1 LAST LOCATION C299
J 0
(-2375 1250);
DISPLAY 0.702128 (-2375 1250);
PAINT YELLOW (-2375 1250);
FORCEPROP 1 LASTPIN (-2425 1250) $PN 1
J 0
(-2415 1230);
DISPLAY 0.808511 (-2415 1230);
PAINT WHITE (-2415 1230);
FORCEPROP 1 LASTPIN (-2425 1050) $PN 2
J 0
(-2415 1030);
DISPLAY 0.808511 (-2415 1030);
PAINT WHITE (-2415 1030);
FORCEPROP 2 LAST $SEC 1
J 0
(-2375 1350);
DISPLAY 0.680851 (-2375 1350);
PAINT MONO (-2375 1350);
DISPLAY INVISIBLE (-2375 1350);
FORCEPROP 0 LAST CDS_SEC 1
J 0
(-2375 1350);
DISPLAY 0.680851 (-2375 1350);
PAINT MONO (-2375 1350);
DISPLAY INVISIBLE (-2375 1350);
FORCEADD UNIVERSAL_GND..1
(-2625 875);
FORCEPROP 3 LASTPIN (-2625 925) SIG_NAME GND\g
J 0
(-2615 935);
DISPLAY 0.659574 (-2615 935);
PAINT MONO (-2615 935);
DISPLAY INVISIBLE (-2615 935);
FORCEPROP 1 LAST PATH I216
J 0
(-2550 875);
DISPLAY 0.872340 (-2550 875);
PAINT AQUA (-2550 875);
DISPLAY INVISIBLE (-2550 875);
FORCEPROP 1 LAST HDL_POWER GND
J 1
(-2641 841);
DISPLAY 0.702128 (-2641 841);
PAINT GREEN (-2641 841);
DISPLAY INVISIBLE (-2641 841);
FORCEPROP 2 LAST CDS_LIB logical_power
J 0
(-2625 875);
DISPLAY INVISIBLE (-2625 875);
FORCEADD OFFPAGE..2
(-2075 1300);
FORCEPROP 2 LAST $XR0 15 
J 0
(-1886 1300);
DISPLAY 0.638298 (-1886 1300);
PAINT MONO (-1886 1300);
FORCEPROP 2 LAST PATH I217
J 0
(-1775 1350);
DISPLAY 1.021277 (-1775 1350);
DISPLAY INVISIBLE (-1775 1350);
FORCEPROP 1 LAST COMMENT_BODY TRUE
J 0
(-2120 1205);
DISPLAY 0.872340 (-2120 1205);
PAINT PEACH (-2120 1205);
DISPLAY INVISIBLE (-2120 1205);
FORCEPROP 1 LAST OFFPAGE TRUE
J 0
(-1750 1175);
DISPLAY 0.872340 (-1750 1175);
PAINT GREEN (-1750 1175);
DISPLAY INVISIBLE (-1750 1175);
FORCEPROP 2 LAST CDS_LIB standard
J 2
(-2075 1300);
DISPLAY INVISIBLE (-2075 1300);
FORCEADD Q_RES..2
R 2
(-2625 1525);
FORCEPROP 1 LAST PART_NUMBER CS22872FB03
J 2
(-2665 1400);
DISPLAY 0.510638 (-2665 1400);
PAINT WHITE (-2665 1400);
FORCEPROP 1 LAST MATERIAL CHIP
J 2
(-2665 1450);
DISPLAY 0.510638 (-2665 1450);
PAINT SKYBLUE (-2665 1450);
FORCEPROP 1 LAST WATTAGE 1/16W
J 2
(-2665 1500);
DISPLAY 0.510638 (-2665 1500);
PAINT SKYBLUE (-2665 1500);
FORCEPROP 1 LAST PACK_TYPE 0402LF
J 2
(-2665 1350);
DISPLAY 0.510638 (-2665 1350);
PAINT SKYBLUE (-2665 1350);
FORCEPROP 1 LAST VALUE 2.87K
J 2
(-2670 1600);
DISPLAY 0.510638 (-2670 1600);
PAINT SKYBLUE (-2670 1600);
FORCEPROP 1 LAST TOLERANCE 1%
J 2
(-2670 1550);
DISPLAY 0.510638 (-2670 1550);
PAINT SKYBLUE (-2670 1550);
FORCEPROP 1 LAST PATH I219
J 2
(-2675 1700);
DISPLAY 0.978723 (-2675 1700);
PAINT WHITE (-2675 1700);
DISPLAY INVISIBLE (-2675 1700);
FORCEPROP 2 LAST CDS_LIB pure_quanta
J 2
(-2625 1525);
DISPLAY INVISIBLE (-2625 1525);
FORCEPROP 1 LAST LOCATION R789
J 2
(-2670 1650);
DISPLAY 0.702128 (-2670 1650);
PAINT YELLOW (-2670 1650);
FORCEPROP 0 LAST $SEC 1
J 0
(-2650 1700);
DISPLAY 0.680851 (-2650 1700);
PAINT MONO (-2650 1700);
DISPLAY INVISIBLE (-2650 1700);
FORCEPROP 0 LAST CDS_SEC 1
J 0
(-2650 1700);
DISPLAY 1.021277 (-2650 1700);
DISPLAY INVISIBLE (-2650 1700);
FORCEPROP 1 LASTPIN (-2625 1625) $PN 1
J 2
(-2630 1587);
DISPLAY 0.808511 (-2630 1587);
PAINT WHITE (-2630 1587);
DISPLAY INVISIBLE (-2630 1587);
FORCEPROP 1 LASTPIN (-2625 1425) $PN 2
J 2
(-2630 1435);
DISPLAY 0.808511 (-2630 1435);
PAINT WHITE (-2630 1435);
DISPLAY INVISIBLE (-2630 1435);
FORCEADD UNIVERSAL_POWER..1
(-500 950);
FORCEPROP 3 LASTPIN (-500 900) SIG_NAME P3V3_RGM\g
J 0
(-490 910);
DISPLAY 0.659574 (-490 910);
PAINT MONO (-490 910);
DISPLAY INVISIBLE (-490 910);
FORCEPROP 1 LAST HDL_POWER P3V3_RGM
J 1
(-500 1000);
DISPLAY 0.702128 (-500 1000);
PAINT GREEN (-500 1000);
FORCEPROP 1 LAST PATH I22
J 0
(-450 975);
DISPLAY 0.872340 (-450 975);
PAINT AQUA (-450 975);
DISPLAY INVISIBLE (-450 975);
FORCEPROP 2 LAST CDS_LIB logical_power
J 0
(-500 950);
DISPLAY INVISIBLE (-500 950);
FORCEADD Q_RES..2
R 2
(-2625 1150);
FORCEPROP 1 LAST PACK_TYPE 0402LF
J 2
(-2665 975);
DISPLAY 0.510638 (-2665 975);
PAINT SKYBLUE (-2665 975);
FORCEPROP 1 LAST PART_NUMBER CS22002FB07
J 2
(-2665 1025);
DISPLAY 0.510638 (-2665 1025);
PAINT WHITE (-2665 1025);
FORCEPROP 1 LAST VALUE 2K
J 2
(-2670 1225);
DISPLAY 0.510638 (-2670 1225);
PAINT SKYBLUE (-2670 1225);
FORCEPROP 1 LAST MATERIAL CHIP
J 2
(-2665 1075);
DISPLAY 0.510638 (-2665 1075);
PAINT SKYBLUE (-2665 1075);
FORCEPROP 1 LAST TOLERANCE 1%
J 2
(-2670 1175);
DISPLAY 0.510638 (-2670 1175);
PAINT SKYBLUE (-2670 1175);
FORCEPROP 1 LAST WATTAGE 1/16W
J 2
(-2665 1125);
DISPLAY 0.510638 (-2665 1125);
PAINT SKYBLUE (-2665 1125);
FORCEPROP 1 LAST PATH I220
J 2
(-2675 1325);
DISPLAY 0.978723 (-2675 1325);
PAINT WHITE (-2675 1325);
DISPLAY INVISIBLE (-2675 1325);
FORCEPROP 2 LAST CDS_LIB pure_quanta
J 2
(-2625 1150);
DISPLAY INVISIBLE (-2625 1150);
FORCEPROP 1 LAST LOCATION R790
J 2
(-2670 1275);
DISPLAY 0.702128 (-2670 1275);
PAINT YELLOW (-2670 1275);
FORCEPROP 0 LAST $SEC 1
J 0
(-2650 1325);
DISPLAY 0.680851 (-2650 1325);
PAINT MONO (-2650 1325);
DISPLAY INVISIBLE (-2650 1325);
FORCEPROP 0 LAST CDS_SEC 1
J 0
(-2650 1325);
DISPLAY 1.021277 (-2650 1325);
DISPLAY INVISIBLE (-2650 1325);
FORCEPROP 1 LASTPIN (-2625 1250) $PN 1
J 2
(-2630 1212);
DISPLAY 0.808511 (-2630 1212);
PAINT WHITE (-2630 1212);
DISPLAY INVISIBLE (-2630 1212);
FORCEPROP 1 LASTPIN (-2625 1050) $PN 2
J 2
(-2630 1060);
DISPLAY 0.808511 (-2630 1060);
PAINT WHITE (-2630 1060);
DISPLAY INVISIBLE (-2630 1060);
FORCEADD UNIVERSAL_POWER..1
(-2625 1725);
FORCEPROP 3 LASTPIN (-2625 1675) SIG_NAME P3V3_AUX\g
J 0
(-2615 1685);
DISPLAY 0.659574 (-2615 1685);
PAINT MONO (-2615 1685);
DISPLAY INVISIBLE (-2615 1685);
FORCEPROP 1 LAST HDL_POWER P3V3_AUX
J 1
(-2625 1775);
DISPLAY 0.702128 (-2625 1775);
PAINT GREEN (-2625 1775);
FORCEPROP 1 LAST PATH I221
J 0
(-2575 1750);
DISPLAY 0.872340 (-2575 1750);
PAINT AQUA (-2575 1750);
DISPLAY INVISIBLE (-2575 1750);
FORCEPROP 2 LAST CDS_LIB logical_power
J 0
(-2625 1725);
DISPLAY INVISIBLE (-2625 1725);
FORCEADD OFFPAGE..1
(-675 2925);
FORCEPROP 2 LAST $XR0 15 
J 0
(-896 2925);
DISPLAY 0.638298 (-896 2925);
PAINT MONO (-896 2925);
FORCEPROP 2 LAST PATH I222
J 0
(-925 2975);
DISPLAY 1.021277 (-925 2975);
DISPLAY INVISIBLE (-925 2975);
FORCEPROP 1 LAST COMMENT_BODY TRUE
J 0
(-550 2825);
DISPLAY 0.872340 (-550 2825);
PAINT PEACH (-550 2825);
DISPLAY INVISIBLE (-550 2825);
FORCEPROP 1 LAST OFFPAGE TRUE
J 0
(-350 2800);
DISPLAY 0.872340 (-350 2800);
PAINT GREEN (-350 2800);
DISPLAY INVISIBLE (-350 2800);
FORCEPROP 2 LAST CDS_LIB standard
J 0
(-675 2925);
DISPLAY INVISIBLE (-675 2925);
FORCEADD Q_RES..2
R 2
(-2625 2525);
FORCEPROP 1 LAST WATTAGE 1/16W
J 2
(-2665 2500);
DISPLAY 0.510638 (-2665 2500);
PAINT SKYBLUE (-2665 2500);
FORCEPROP 1 LAST MATERIAL CHIP
J 2
(-2665 2450);
DISPLAY 0.510638 (-2665 2450);
PAINT SKYBLUE (-2665 2450);
FORCEPROP 1 LAST TOLERANCE 1%
J 2
(-2670 2550);
DISPLAY 0.510638 (-2670 2550);
PAINT SKYBLUE (-2670 2550);
FORCEPROP 1 LAST VALUE 5.36K
J 2
(-2670 2600);
DISPLAY 0.510638 (-2670 2600);
PAINT SKYBLUE (-2670 2600);
FORCEPROP 1 LAST PART_NUMBER CS25362FB02
J 2
(-2665 2400);
DISPLAY 0.510638 (-2665 2400);
PAINT WHITE (-2665 2400);
FORCEPROP 1 LAST PACK_TYPE 0402LF
J 2
(-2665 2350);
DISPLAY 0.510638 (-2665 2350);
PAINT SKYBLUE (-2665 2350);
FORCEPROP 1 LAST PATH I223
J 2
(-2675 2700);
DISPLAY 0.978723 (-2675 2700);
PAINT WHITE (-2675 2700);
DISPLAY INVISIBLE (-2675 2700);
FORCEPROP 2 LAST CDS_LIB pure_quanta
J 2
(-2625 2525);
DISPLAY INVISIBLE (-2625 2525);
FORCEPROP 1 LAST LOCATION R787
J 2
(-2670 2650);
DISPLAY 0.702128 (-2670 2650);
PAINT YELLOW (-2670 2650);
FORCEPROP 0 LAST $SEC 1
J 0
(-2650 2700);
DISPLAY 0.680851 (-2650 2700);
PAINT MONO (-2650 2700);
DISPLAY INVISIBLE (-2650 2700);
FORCEPROP 0 LAST CDS_SEC 1
J 0
(-2650 2700);
DISPLAY 1.021277 (-2650 2700);
DISPLAY INVISIBLE (-2650 2700);
FORCEPROP 1 LASTPIN (-2625 2625) $PN 1
J 2
(-2630 2587);
DISPLAY 0.808511 (-2630 2587);
PAINT WHITE (-2630 2587);
DISPLAY INVISIBLE (-2630 2587);
FORCEPROP 1 LASTPIN (-2625 2425) $PN 2
J 2
(-2630 2435);
DISPLAY 0.808511 (-2630 2435);
PAINT WHITE (-2630 2435);
DISPLAY INVISIBLE (-2630 2435);
FORCEADD OFFPAGE..1
(-675 2875);
FORCEPROP 2 LAST $XR0 15 
J 0
(-896 2875);
DISPLAY 0.638298 (-896 2875);
PAINT MONO (-896 2875);
FORCEPROP 2 LAST PATH I228
J 0
(-925 2925);
DISPLAY 1.021277 (-925 2925);
DISPLAY INVISIBLE (-925 2925);
FORCEPROP 1 LAST COMMENT_BODY TRUE
J 0
(-550 2775);
DISPLAY 0.872340 (-550 2775);
PAINT PEACH (-550 2775);
DISPLAY INVISIBLE (-550 2775);
FORCEPROP 1 LAST OFFPAGE TRUE
J 0
(-350 2750);
DISPLAY 0.872340 (-350 2750);
PAINT GREEN (-350 2750);
DISPLAY INVISIBLE (-350 2750);
FORCEPROP 2 LAST CDS_LIB standard
J 0
(-675 2875);
DISPLAY INVISIBLE (-675 2875);
FORCEADD OFFPAGE..1
(-675 2825);
FORCEPROP 2 LAST $XR0 15 
J 0
(-896 2825);
DISPLAY 0.638298 (-896 2825);
PAINT MONO (-896 2825);
FORCEPROP 2 LAST PATH I229
J 0
(-925 2875);
DISPLAY 1.021277 (-925 2875);
DISPLAY INVISIBLE (-925 2875);
FORCEPROP 1 LAST COMMENT_BODY TRUE
J 0
(-550 2725);
DISPLAY 0.872340 (-550 2725);
PAINT PEACH (-550 2725);
DISPLAY INVISIBLE (-550 2725);
FORCEPROP 1 LAST OFFPAGE TRUE
J 0
(-350 2700);
DISPLAY 0.872340 (-350 2700);
PAINT GREEN (-350 2700);
DISPLAY INVISIBLE (-350 2700);
FORCEPROP 2 LAST CDS_LIB standard
J 0
(-675 2825);
DISPLAY INVISIBLE (-675 2825);
FORCEADD UNIVERSAL_GND..1
(-175 500);
FORCEPROP 3 LASTPIN (-175 550) SIG_NAME GND\g
J 0
(-165 560);
DISPLAY 0.659574 (-165 560);
PAINT MONO (-165 560);
DISPLAY INVISIBLE (-165 560);
FORCEPROP 1 LAST PATH I23
J 0
(-100 500);
DISPLAY 0.872340 (-100 500);
PAINT AQUA (-100 500);
DISPLAY INVISIBLE (-100 500);
FORCEPROP 1 LAST HDL_POWER GND
J 1
(-150 425);
DISPLAY 0.702128 (-150 425);
PAINT GREEN (-150 425);
DISPLAY INVISIBLE (-150 425);
FORCEPROP 2 LAST CDS_LIB logical_power
J 0
(-175 500);
DISPLAY INVISIBLE (-175 500);
FORCEADD OFFPAGE..2
(-2075 175);
FORCEPROP 2 LAST $XR0 15 
J 0
(-1886 175);
DISPLAY 0.638298 (-1886 175);
PAINT MONO (-1886 175);
FORCEPROP 2 LAST PATH I234
J 0
(-1775 225);
DISPLAY 1.021277 (-1775 225);
DISPLAY INVISIBLE (-1775 225);
FORCEPROP 1 LAST COMMENT_BODY TRUE
J 0
(-2120 80);
DISPLAY 0.872340 (-2120 80);
PAINT PEACH (-2120 80);
DISPLAY INVISIBLE (-2120 80);
FORCEPROP 1 LAST OFFPAGE TRUE
J 0
(-1750 50);
DISPLAY 0.872340 (-1750 50);
PAINT GREEN (-1750 50);
DISPLAY INVISIBLE (-1750 50);
FORCEPROP 2 LAST CDS_LIB standard
J 2
(-2075 175);
DISPLAY INVISIBLE (-2075 175);
FORCEADD Q_CAP..1
(-2425 25);
FORCEPROP 1 LAST TOLERANCE 10%
J 0
(-2375 -25);
DISPLAY 0.510638 (-2375 -25);
PAINT SKYBLUE (-2375 -25);
FORCEPROP 1 LAST PACK_TYPE 0402
J 0
(-2375 -125);
DISPLAY 0.510638 (-2375 -125);
PAINT SKYBLUE (-2375 -125);
FORCEPROP 1 LAST MATERIAL X7R
J 0
(-2375 -75);
DISPLAY 0.510638 (-2375 -75);
PAINT SKYBLUE (-2375 -75);
FORCEPROP 1 LAST VALUE 0.1UF
J 0
(-2375 75);
DISPLAY 0.510638 (-2375 75);
PAINT SKYBLUE (-2375 75);
FORCEPROP 1 LAST VOLTAGE 25V
J 0
(-2375 25);
DISPLAY 0.510638 (-2375 25);
PAINT SKYBLUE (-2375 25);
FORCEPROP 1 LAST PART_NUMBER CH4104K1B00
J 0
(-2375 -175);
DISPLAY 0.510638 (-2375 -175);
PAINT WHITE (-2375 -175);
FORCEPROP 1 LAST PATH I235
J 0
(-2375 175);
DISPLAY 0.978723 (-2375 175);
PAINT WHITE (-2375 175);
DISPLAY INVISIBLE (-2375 175);
FORCEPROP 2 LAST CDS_LIB pure_quanta
J 0
(-2425 25);
DISPLAY INVISIBLE (-2425 25);
FORCEPROP 1 LAST LOCATION C303
J 0
(-2375 125);
DISPLAY 0.702128 (-2375 125);
PAINT YELLOW (-2375 125);
FORCEPROP 1 LASTPIN (-2425 125) $PN 1
J 0
(-2415 105);
DISPLAY 0.808511 (-2415 105);
PAINT WHITE (-2415 105);
FORCEPROP 1 LASTPIN (-2425 -75) $PN 2
J 0
(-2415 -95);
DISPLAY 0.808511 (-2415 -95);
PAINT WHITE (-2415 -95);
FORCEPROP 2 LAST $SEC 1
J 0
(-2375 225);
DISPLAY 0.680851 (-2375 225);
PAINT MONO (-2375 225);
DISPLAY INVISIBLE (-2375 225);
FORCEPROP 0 LAST CDS_SEC 1
J 0
(-2375 225);
DISPLAY 0.680851 (-2375 225);
PAINT MONO (-2375 225);
DISPLAY INVISIBLE (-2375 225);
FORCEADD Q_RES..2
R 2
(-2625 25);
FORCEPROP 1 LAST PART_NUMBER CS22002FB07
J 2
(-2665 -100);
DISPLAY 0.510638 (-2665 -100);
PAINT WHITE (-2665 -100);
FORCEPROP 1 LAST PACK_TYPE 0402LF
J 2
(-2665 -150);
DISPLAY 0.510638 (-2665 -150);
PAINT SKYBLUE (-2665 -150);
FORCEPROP 1 LAST MATERIAL CHIP
J 2
(-2665 -50);
DISPLAY 0.510638 (-2665 -50);
PAINT SKYBLUE (-2665 -50);
FORCEPROP 1 LAST TOLERANCE 1%
J 2
(-2670 50);
DISPLAY 0.510638 (-2670 50);
PAINT SKYBLUE (-2670 50);
FORCEPROP 1 LAST VALUE 2K
J 2
(-2670 100);
DISPLAY 0.510638 (-2670 100);
PAINT SKYBLUE (-2670 100);
FORCEPROP 1 LAST WATTAGE 1/16W
J 2
(-2665 0);
DISPLAY 0.510638 (-2665 0);
PAINT SKYBLUE (-2665 0);
FORCEPROP 1 LAST PATH I236
J 2
(-2675 200);
DISPLAY 0.978723 (-2675 200);
PAINT WHITE (-2675 200);
DISPLAY INVISIBLE (-2675 200);
FORCEPROP 2 LAST CDS_LIB pure_quanta
J 2
(-2625 25);
DISPLAY INVISIBLE (-2625 25);
FORCEPROP 1 LAST LOCATION R792
J 2
(-2670 150);
DISPLAY 0.702128 (-2670 150);
PAINT YELLOW (-2670 150);
FORCEPROP 0 LAST $SEC 1
J 0
(-2650 200);
DISPLAY 0.680851 (-2650 200);
PAINT MONO (-2650 200);
DISPLAY INVISIBLE (-2650 200);
FORCEPROP 0 LAST CDS_SEC 1
J 0
(-2650 200);
DISPLAY 1.021277 (-2650 200);
DISPLAY INVISIBLE (-2650 200);
FORCEPROP 1 LASTPIN (-2625 125) $PN 1
J 2
(-2630 87);
DISPLAY 0.808511 (-2630 87);
PAINT WHITE (-2630 87);
DISPLAY INVISIBLE (-2630 87);
FORCEPROP 1 LASTPIN (-2625 -75) $PN 2
J 2
(-2630 -65);
DISPLAY 0.808511 (-2630 -65);
PAINT WHITE (-2630 -65);
DISPLAY INVISIBLE (-2630 -65);
FORCEADD UNIVERSAL_GND..1
(-2625 -250);
FORCEPROP 3 LASTPIN (-2625 -200) SIG_NAME GND\g
J 0
(-2615 -190);
DISPLAY 0.659574 (-2615 -190);
PAINT MONO (-2615 -190);
DISPLAY INVISIBLE (-2615 -190);
FORCEPROP 1 LAST PATH I237
J 0
(-2550 -250);
DISPLAY 0.872340 (-2550 -250);
PAINT AQUA (-2550 -250);
DISPLAY INVISIBLE (-2550 -250);
FORCEPROP 1 LAST HDL_POWER GND
J 1
(-2641 -284);
DISPLAY 0.702128 (-2641 -284);
PAINT GREEN (-2641 -284);
DISPLAY INVISIBLE (-2641 -284);
FORCEPROP 2 LAST CDS_LIB logical_power
J 0
(-2625 -250);
DISPLAY INVISIBLE (-2625 -250);
FORCEADD OFFPAGE..2
(-2075 -925);
FORCEPROP 2 LAST $XR0 15 
J 0
(-1886 -925);
DISPLAY 0.638298 (-1886 -925);
PAINT MONO (-1886 -925);
FORCEPROP 2 LAST PATH I238
J 0
(-1775 -875);
DISPLAY 1.021277 (-1775 -875);
DISPLAY INVISIBLE (-1775 -875);
FORCEPROP 1 LAST COMMENT_BODY TRUE
J 0
(-2120 -1020);
DISPLAY 0.872340 (-2120 -1020);
PAINT PEACH (-2120 -1020);
DISPLAY INVISIBLE (-2120 -1020);
FORCEPROP 1 LAST OFFPAGE TRUE
J 0
(-1750 -1050);
DISPLAY 0.872340 (-1750 -1050);
PAINT GREEN (-1750 -1050);
DISPLAY INVISIBLE (-1750 -1050);
FORCEPROP 2 LAST CDS_LIB standard
J 2
(-2075 -925);
DISPLAY INVISIBLE (-2075 -925);
FORCEADD Q_CAP..1
(-175 800);
FORCEPROP 1 LAST VALUE 0.1UF
J 0
(-125 850);
DISPLAY 0.510638 (-125 850);
PAINT SKYBLUE (-125 850);
FORCEPROP 1 LAST PACK_TYPE 0402
J 0
(-125 650);
DISPLAY 0.510638 (-125 650);
PAINT SKYBLUE (-125 650);
FORCEPROP 1 LAST MATERIAL X7R
J 0
(-125 700);
DISPLAY 0.510638 (-125 700);
PAINT SKYBLUE (-125 700);
FORCEPROP 1 LAST TOLERANCE 10%
J 0
(-125 750);
DISPLAY 0.510638 (-125 750);
PAINT SKYBLUE (-125 750);
FORCEPROP 1 LAST VOLTAGE 25V
J 0
(-125 800);
DISPLAY 0.510638 (-125 800);
PAINT SKYBLUE (-125 800);
FORCEPROP 1 LAST PATH I24
J 0
(-125 950);
DISPLAY 0.978723 (-125 950);
PAINT WHITE (-125 950);
DISPLAY INVISIBLE (-125 950);
FORCEPROP 2 LAST CDS_LIB pure_quanta
J 0
(-175 800);
DISPLAY INVISIBLE (-175 800);
FORCEPROP 1 LAST PART_NUMBER CH4104K1B00
J 0
(-125 650);
DISPLAY 0.510638 (-125 650);
PAINT WHITE (-125 650);
DISPLAY INVISIBLE (-125 650);
FORCEPROP 1 LAST LOCATION C37
J 0
(-125 900);
DISPLAY 0.702128 (-125 900);
PAINT YELLOW (-125 900);
FORCEPROP 1 LASTPIN (-175 900) $PN 1
J 0
(-165 880);
DISPLAY 0.808511 (-165 880);
PAINT WHITE (-165 880);
FORCEPROP 1 LASTPIN (-175 700) $PN 2
J 0
(-165 680);
DISPLAY 0.808511 (-165 680);
PAINT WHITE (-165 680);
FORCEPROP 2 LAST $SEC 1
J 0
(-125 1000);
DISPLAY 0.680851 (-125 1000);
PAINT MONO (-125 1000);
DISPLAY INVISIBLE (-125 1000);
FORCEPROP 0 LAST CDS_SEC 1
J 0
(-125 1000);
DISPLAY 0.680851 (-125 1000);
PAINT MONO (-125 1000);
DISPLAY INVISIBLE (-125 1000);
FORCEADD Q_CAP..1
(-2425 -1075);
FORCEPROP 1 LAST TOLERANCE 10%
J 0
(-2375 -1125);
DISPLAY 0.510638 (-2375 -1125);
PAINT SKYBLUE (-2375 -1125);
FORCEPROP 1 LAST PACK_TYPE 0402
J 0
(-2375 -1225);
DISPLAY 0.510638 (-2375 -1225);
PAINT SKYBLUE (-2375 -1225);
FORCEPROP 1 LAST MATERIAL X7R
J 0
(-2375 -1175);
DISPLAY 0.510638 (-2375 -1175);
PAINT SKYBLUE (-2375 -1175);
FORCEPROP 1 LAST VOLTAGE 25V
J 0
(-2375 -1075);
DISPLAY 0.510638 (-2375 -1075);
PAINT SKYBLUE (-2375 -1075);
FORCEPROP 1 LAST VALUE 0.1UF
J 0
(-2375 -1025);
DISPLAY 0.510638 (-2375 -1025);
PAINT SKYBLUE (-2375 -1025);
FORCEPROP 1 LAST PART_NUMBER CH4104K1B00
J 0
(-2375 -1275);
DISPLAY 0.510638 (-2375 -1275);
PAINT WHITE (-2375 -1275);
FORCEPROP 1 LAST PATH I240
J 0
(-2375 -925);
DISPLAY 0.978723 (-2375 -925);
PAINT WHITE (-2375 -925);
DISPLAY INVISIBLE (-2375 -925);
FORCEPROP 2 LAST CDS_LIB pure_quanta
J 0
(-2425 -1075);
DISPLAY INVISIBLE (-2425 -1075);
FORCEPROP 1 LAST LOCATION C307
J 0
(-2375 -975);
DISPLAY 0.702128 (-2375 -975);
PAINT YELLOW (-2375 -975);
FORCEPROP 1 LASTPIN (-2425 -975) $PN 1
J 0
(-2415 -995);
DISPLAY 0.808511 (-2415 -995);
PAINT WHITE (-2415 -995);
FORCEPROP 1 LASTPIN (-2425 -1175) $PN 2
J 0
(-2415 -1195);
DISPLAY 0.808511 (-2415 -1195);
PAINT WHITE (-2415 -1195);
FORCEPROP 2 LAST $SEC 1
J 0
(-2375 -875);
DISPLAY 0.680851 (-2375 -875);
PAINT MONO (-2375 -875);
DISPLAY INVISIBLE (-2375 -875);
FORCEPROP 0 LAST CDS_SEC 1
J 0
(-2375 -875);
DISPLAY 0.680851 (-2375 -875);
PAINT MONO (-2375 -875);
DISPLAY INVISIBLE (-2375 -875);
FORCEADD Q_RES..2
R 2
(-2625 -1075);
FORCEPROP 1 LAST WATTAGE 1/16W
J 2
(-2665 -1100);
DISPLAY 0.510638 (-2665 -1100);
PAINT SKYBLUE (-2665 -1100);
FORCEPROP 1 LAST PACK_TYPE 0402LF
J 2
(-2665 -1250);
DISPLAY 0.510638 (-2665 -1250);
PAINT SKYBLUE (-2665 -1250);
FORCEPROP 1 LAST MATERIAL CHIP
J 2
(-2665 -1150);
DISPLAY 0.510638 (-2665 -1150);
PAINT SKYBLUE (-2665 -1150);
FORCEPROP 1 LAST TOLERANCE 1%
J 2
(-2670 -1050);
DISPLAY 0.510638 (-2670 -1050);
PAINT SKYBLUE (-2670 -1050);
FORCEPROP 1 LAST VALUE 2K
J 2
(-2670 -1000);
DISPLAY 0.510638 (-2670 -1000);
PAINT SKYBLUE (-2670 -1000);
FORCEPROP 1 LAST PART_NUMBER CS22002FB07
J 2
(-2665 -1200);
DISPLAY 0.510638 (-2665 -1200);
PAINT WHITE (-2665 -1200);
FORCEPROP 1 LAST PATH I242
J 2
(-2675 -900);
DISPLAY 0.978723 (-2675 -900);
PAINT WHITE (-2675 -900);
DISPLAY INVISIBLE (-2675 -900);
FORCEPROP 2 LAST CDS_LIB pure_quanta
J 2
(-2625 -1075);
DISPLAY INVISIBLE (-2625 -1075);
FORCEPROP 1 LAST LOCATION R794
J 2
(-2670 -950);
DISPLAY 0.702128 (-2670 -950);
PAINT YELLOW (-2670 -950);
FORCEPROP 0 LAST $SEC 1
J 0
(-2650 -900);
DISPLAY 0.680851 (-2650 -900);
PAINT MONO (-2650 -900);
DISPLAY INVISIBLE (-2650 -900);
FORCEPROP 0 LAST CDS_SEC 1
J 0
(-2650 -900);
DISPLAY 1.021277 (-2650 -900);
DISPLAY INVISIBLE (-2650 -900);
FORCEPROP 1 LASTPIN (-2625 -975) $PN 1
J 2
(-2630 -1013);
DISPLAY 0.808511 (-2630 -1013);
PAINT WHITE (-2630 -1013);
DISPLAY INVISIBLE (-2630 -1013);
FORCEPROP 1 LASTPIN (-2625 -1175) $PN 2
J 2
(-2630 -1165);
DISPLAY 0.808511 (-2630 -1165);
PAINT WHITE (-2630 -1165);
DISPLAY INVISIBLE (-2630 -1165);
FORCEADD UNIVERSAL_GND..1
(-2625 -1350);
FORCEPROP 3 LASTPIN (-2625 -1300) SIG_NAME GND\g
J 0
(-2615 -1290);
DISPLAY 0.659574 (-2615 -1290);
PAINT MONO (-2615 -1290);
DISPLAY INVISIBLE (-2615 -1290);
FORCEPROP 1 LAST PATH I243
J 0
(-2550 -1350);
DISPLAY 0.872340 (-2550 -1350);
PAINT AQUA (-2550 -1350);
DISPLAY INVISIBLE (-2550 -1350);
FORCEPROP 1 LAST HDL_POWER GND
J 1
(-2641 -1384);
DISPLAY 0.702128 (-2641 -1384);
PAINT GREEN (-2641 -1384);
DISPLAY INVISIBLE (-2641 -1384);
FORCEPROP 2 LAST CDS_LIB logical_power
J 0
(-2625 -1350);
DISPLAY INVISIBLE (-2625 -1350);
FORCEADD Q_RES..2
R 2
(-2625 -700);
FORCEPROP 1 LAST PART_NUMBER CS16652FB00
J 2
(-2665 -825);
DISPLAY 0.510638 (-2665 -825);
PAINT WHITE (-2665 -825);
FORCEPROP 1 LAST PACK_TYPE 0402LF
J 2
(-2665 -875);
DISPLAY 0.510638 (-2665 -875);
PAINT SKYBLUE (-2665 -875);
FORCEPROP 1 LAST MATERIAL CHIP
J 2
(-2665 -775);
DISPLAY 0.510638 (-2665 -775);
PAINT SKYBLUE (-2665 -775);
FORCEPROP 1 LAST VALUE 665
J 2
(-2670 -625);
DISPLAY 0.510638 (-2670 -625);
PAINT SKYBLUE (-2670 -625);
FORCEPROP 1 LAST TOLERANCE 1%
J 2
(-2670 -675);
DISPLAY 0.510638 (-2670 -675);
PAINT SKYBLUE (-2670 -675);
FORCEPROP 1 LAST WATTAGE 1/16W
J 2
(-2665 -725);
DISPLAY 0.510638 (-2665 -725);
PAINT SKYBLUE (-2665 -725);
FORCEPROP 1 LAST PATH I244
J 2
(-2675 -525);
DISPLAY 0.978723 (-2675 -525);
PAINT WHITE (-2675 -525);
DISPLAY INVISIBLE (-2675 -525);
FORCEPROP 2 LAST CDS_LIB pure_quanta
J 2
(-2625 -700);
DISPLAY INVISIBLE (-2625 -700);
FORCEPROP 1 LAST LOCATION R793
J 2
(-2670 -575);
DISPLAY 0.702128 (-2670 -575);
PAINT YELLOW (-2670 -575);
FORCEPROP 0 LAST $SEC 1
J 0
(-2650 -525);
DISPLAY 0.680851 (-2650 -525);
PAINT MONO (-2650 -525);
DISPLAY INVISIBLE (-2650 -525);
FORCEPROP 0 LAST CDS_SEC 1
J 0
(-2650 -525);
DISPLAY 1.021277 (-2650 -525);
DISPLAY INVISIBLE (-2650 -525);
FORCEPROP 1 LASTPIN (-2625 -600) $PN 1
J 2
(-2630 -638);
DISPLAY 0.808511 (-2630 -638);
PAINT WHITE (-2630 -638);
DISPLAY INVISIBLE (-2630 -638);
FORCEPROP 1 LASTPIN (-2625 -800) $PN 2
J 2
(-2630 -790);
DISPLAY 0.808511 (-2630 -790);
PAINT WHITE (-2630 -790);
DISPLAY INVISIBLE (-2630 -790);
FORCEADD Q_RES..2
R 2
(-2625 400);
FORCEPROP 1 LAST PART_NUMBER CS21692FB04
J 2
(-2665 275);
DISPLAY 0.510638 (-2665 275);
PAINT WHITE (-2665 275);
FORCEPROP 1 LAST PACK_TYPE 0402LF
J 2
(-2665 225);
DISPLAY 0.510638 (-2665 225);
PAINT SKYBLUE (-2665 225);
FORCEPROP 1 LAST TOLERANCE 1%
J 2
(-2670 425);
DISPLAY 0.510638 (-2670 425);
PAINT SKYBLUE (-2670 425);
FORCEPROP 1 LAST VALUE 1.69K
J 2
(-2670 475);
DISPLAY 0.510638 (-2670 475);
PAINT SKYBLUE (-2670 475);
FORCEPROP 1 LAST WATTAGE 1/16W
J 2
(-2665 375);
DISPLAY 0.510638 (-2665 375);
PAINT SKYBLUE (-2665 375);
FORCEPROP 1 LAST MATERIAL CHIP
J 2
(-2665 325);
DISPLAY 0.510638 (-2665 325);
PAINT SKYBLUE (-2665 325);
FORCEPROP 1 LAST PATH I245
J 2
(-2675 575);
DISPLAY 0.978723 (-2675 575);
PAINT WHITE (-2675 575);
DISPLAY INVISIBLE (-2675 575);
FORCEPROP 2 LAST CDS_LIB pure_quanta
J 2
(-2625 400);
DISPLAY INVISIBLE (-2625 400);
FORCEPROP 1 LAST LOCATION R791
J 2
(-2670 525);
DISPLAY 0.702128 (-2670 525);
PAINT YELLOW (-2670 525);
FORCEPROP 0 LAST $SEC 1
J 0
(-2650 575);
DISPLAY 0.680851 (-2650 575);
PAINT MONO (-2650 575);
DISPLAY INVISIBLE (-2650 575);
FORCEPROP 0 LAST CDS_SEC 1
J 0
(-2650 575);
DISPLAY 1.021277 (-2650 575);
DISPLAY INVISIBLE (-2650 575);
FORCEPROP 1 LASTPIN (-2625 500) $PN 1
J 2
(-2630 462);
DISPLAY 0.808511 (-2630 462);
PAINT WHITE (-2630 462);
DISPLAY INVISIBLE (-2630 462);
FORCEPROP 1 LASTPIN (-2625 300) $PN 2
J 2
(-2630 310);
DISPLAY 0.808511 (-2630 310);
PAINT WHITE (-2630 310);
DISPLAY INVISIBLE (-2630 310);
FORCEADD OFFPAGE..2
(-1100 1175);
FORCEPROP 2 LAST $XR0 15 
J 0
(-911 1175);
DISPLAY 0.638298 (-911 1175);
PAINT MONO (-911 1175);
FORCEPROP 2 LAST PATH I246
J 0
(-800 1225);
DISPLAY 1.021277 (-800 1225);
DISPLAY INVISIBLE (-800 1225);
FORCEPROP 1 LAST COMMENT_BODY TRUE
J 0
(-1145 1080);
DISPLAY 0.872340 (-1145 1080);
PAINT PEACH (-1145 1080);
DISPLAY INVISIBLE (-1145 1080);
FORCEPROP 1 LAST OFFPAGE TRUE
J 0
(-775 1050);
DISPLAY 0.872340 (-775 1050);
PAINT GREEN (-775 1050);
DISPLAY INVISIBLE (-775 1050);
FORCEPROP 2 LAST CDS_LIB standard
J 2
(-1100 1175);
DISPLAY INVISIBLE (-1100 1175);
FORCEADD Q_CAP..1
(-1650 1025);
FORCEPROP 1 LAST PART_NUMBER CH4104K1B00
J 0
(-1600 825);
DISPLAY 0.510638 (-1600 825);
PAINT WHITE (-1600 825);
FORCEPROP 1 LAST MATERIAL X7R
J 0
(-1600 925);
DISPLAY 0.510638 (-1600 925);
PAINT SKYBLUE (-1600 925);
FORCEPROP 1 LAST TOLERANCE 10%
J 0
(-1600 975);
DISPLAY 0.510638 (-1600 975);
PAINT SKYBLUE (-1600 975);
FORCEPROP 1 LAST VALUE 0.1UF
J 0
(-1600 1075);
DISPLAY 0.510638 (-1600 1075);
PAINT SKYBLUE (-1600 1075);
FORCEPROP 1 LAST VOLTAGE 25V
J 0
(-1600 1025);
DISPLAY 0.510638 (-1600 1025);
PAINT SKYBLUE (-1600 1025);
FORCEPROP 1 LAST PACK_TYPE 0402
J 0
(-1600 875);
DISPLAY 0.510638 (-1600 875);
PAINT SKYBLUE (-1600 875);
FORCEPROP 1 LAST PATH I247
J 0
(-1600 1175);
DISPLAY 0.978723 (-1600 1175);
PAINT WHITE (-1600 1175);
DISPLAY INVISIBLE (-1600 1175);
FORCEPROP 2 LAST CDS_LIB pure_quanta
J 0
(-1650 1025);
DISPLAY INVISIBLE (-1650 1025);
FORCEPROP 1 LAST LOCATION C309
J 0
(-1600 1125);
DISPLAY 0.702128 (-1600 1125);
PAINT YELLOW (-1600 1125);
FORCEPROP 1 LASTPIN (-1650 1125) $PN 1
J 0
(-1640 1105);
DISPLAY 0.808511 (-1640 1105);
PAINT WHITE (-1640 1105);
FORCEPROP 1 LASTPIN (-1650 925) $PN 2
J 0
(-1640 905);
DISPLAY 0.808511 (-1640 905);
PAINT WHITE (-1640 905);
FORCEPROP 2 LAST $SEC 1
J 0
(-1600 1225);
DISPLAY 0.680851 (-1600 1225);
PAINT MONO (-1600 1225);
DISPLAY INVISIBLE (-1600 1225);
FORCEPROP 0 LAST CDS_SEC 1
J 0
(-1600 1225);
DISPLAY 0.680851 (-1600 1225);
PAINT MONO (-1600 1225);
DISPLAY INVISIBLE (-1600 1225);
FORCEADD UNIVERSAL_POWER..1
(-175 1150);
FORCEPROP 3 LASTPIN (-175 1100) SIG_NAME P3V3_RGM\g
J 0
(-165 1110);
DISPLAY 0.659574 (-165 1110);
PAINT MONO (-165 1110);
DISPLAY INVISIBLE (-165 1110);
FORCEPROP 1 LAST HDL_POWER P3V3_RGM
J 1
(-175 1200);
DISPLAY 0.702128 (-175 1200);
PAINT GREEN (-175 1200);
FORCEPROP 1 LAST PATH I25
J 0
(-125 1175);
DISPLAY 0.872340 (-125 1175);
PAINT AQUA (-125 1175);
DISPLAY INVISIBLE (-125 1175);
FORCEPROP 2 LAST CDS_LIB logical_power
J 0
(-175 1150);
DISPLAY INVISIBLE (-175 1150);
FORCEADD UNIVERSAL_GND..1
(-1650 750);
FORCEPROP 3 LASTPIN (-1650 800) SIG_NAME GND\g
J 0
(-1640 810);
DISPLAY 0.659574 (-1640 810);
PAINT MONO (-1640 810);
DISPLAY INVISIBLE (-1640 810);
FORCEPROP 1 LAST PATH I251
J 0
(-1575 750);
DISPLAY 0.872340 (-1575 750);
PAINT AQUA (-1575 750);
DISPLAY INVISIBLE (-1575 750);
FORCEPROP 1 LAST HDL_POWER GND
J 1
(-1666 716);
DISPLAY 0.702128 (-1666 716);
PAINT GREEN (-1666 716);
DISPLAY INVISIBLE (-1666 716);
FORCEPROP 2 LAST CDS_LIB logical_power
J 0
(-1650 750);
DISPLAY INVISIBLE (-1650 750);
FORCEADD Q_RES..2
(-1650 1425);
FORCEPROP 1 LAST TOLERANCE 1%
J 0
(-1605 1450);
DISPLAY 0.510638 (-1605 1450);
PAINT SKYBLUE (-1605 1450);
FORCEPROP 1 LAST VALUE 1K
J 0
(-1605 1500);
DISPLAY 0.510638 (-1605 1500);
PAINT SKYBLUE (-1605 1500);
FORCEPROP 1 LAST MATERIAL CHIP
J 0
(-1610 1350);
DISPLAY 0.510638 (-1610 1350);
PAINT SKYBLUE (-1610 1350);
FORCEPROP 1 LAST WATTAGE 1/16W
J 0
(-1610 1400);
DISPLAY 0.510638 (-1610 1400);
PAINT SKYBLUE (-1610 1400);
FORCEPROP 1 LAST PACK_TYPE 0402LF
J 0
(-1610 1250);
DISPLAY 0.510638 (-1610 1250);
PAINT SKYBLUE (-1610 1250);
FORCEPROP 1 LAST PART_NUMBER CS21002FB06
J 0
(-1610 1300);
DISPLAY 0.510638 (-1610 1300);
PAINT WHITE (-1610 1300);
FORCEPROP 1 LAST PATH I252
J 0
(-1600 1600);
DISPLAY 0.978723 (-1600 1600);
PAINT WHITE (-1600 1600);
DISPLAY INVISIBLE (-1600 1600);
FORCEPROP 2 LAST CDS_LIB pure_quanta
J 0
(-1650 1425);
DISPLAY INVISIBLE (-1650 1425);
FORCEPROP 1 LAST LOCATION R795
J 0
(-1605 1550);
DISPLAY 0.702128 (-1605 1550);
PAINT YELLOW (-1605 1550);
FORCEPROP 0 LAST $SEC 1
J 0
(-1600 1600);
DISPLAY 0.680851 (-1600 1600);
PAINT MONO (-1600 1600);
DISPLAY INVISIBLE (-1600 1600);
FORCEPROP 0 LAST CDS_SEC 1
J 0
(-1600 1600);
DISPLAY 1.021277 (-1600 1600);
DISPLAY INVISIBLE (-1600 1600);
FORCEPROP 1 LASTPIN (-1650 1525) $PN 1
J 0
(-1645 1487);
DISPLAY 0.808511 (-1645 1487);
PAINT WHITE (-1645 1487);
DISPLAY INVISIBLE (-1645 1487);
FORCEPROP 1 LASTPIN (-1650 1325) $PN 2
J 0
(-1645 1335);
DISPLAY 0.808511 (-1645 1335);
PAINT WHITE (-1645 1335);
DISPLAY INVISIBLE (-1645 1335);
FORCEADD OFFPAGE..2
(-1075 75);
FORCEPROP 2 LAST $XR0 15 
J 0
(-886 75);
DISPLAY 0.638298 (-886 75);
PAINT MONO (-886 75);
FORCEPROP 2 LAST PATH I254
J 0
(-775 125);
DISPLAY 1.021277 (-775 125);
DISPLAY INVISIBLE (-775 125);
FORCEPROP 1 LAST COMMENT_BODY TRUE
J 0
(-1120 -20);
DISPLAY 0.872340 (-1120 -20);
PAINT PEACH (-1120 -20);
DISPLAY INVISIBLE (-1120 -20);
FORCEPROP 1 LAST OFFPAGE TRUE
J 0
(-750 -50);
DISPLAY 0.872340 (-750 -50);
PAINT GREEN (-750 -50);
DISPLAY INVISIBLE (-750 -50);
FORCEPROP 2 LAST CDS_LIB standard
J 2
(-1075 75);
DISPLAY INVISIBLE (-1075 75);
FORCEADD Q_RES..2
(-1625 325);
FORCEPROP 1 LAST VALUE 1K
J 0
(-1580 400);
DISPLAY 0.510638 (-1580 400);
PAINT SKYBLUE (-1580 400);
FORCEPROP 1 LAST TOLERANCE 1%
J 0
(-1580 350);
DISPLAY 0.510638 (-1580 350);
PAINT SKYBLUE (-1580 350);
FORCEPROP 1 LAST WATTAGE 1/16W
J 0
(-1585 300);
DISPLAY 0.510638 (-1585 300);
PAINT SKYBLUE (-1585 300);
FORCEPROP 1 LAST MATERIAL CHIP
J 0
(-1585 250);
DISPLAY 0.510638 (-1585 250);
PAINT SKYBLUE (-1585 250);
FORCEPROP 1 LAST PACK_TYPE 0402LF
J 0
(-1585 150);
DISPLAY 0.510638 (-1585 150);
PAINT SKYBLUE (-1585 150);
FORCEPROP 1 LAST PART_NUMBER CS21002FB06
J 0
(-1585 200);
DISPLAY 0.510638 (-1585 200);
PAINT WHITE (-1585 200);
FORCEPROP 1 LAST PATH I255
J 0
(-1575 500);
DISPLAY 0.978723 (-1575 500);
PAINT WHITE (-1575 500);
DISPLAY INVISIBLE (-1575 500);
FORCEPROP 2 LAST CDS_LIB pure_quanta
J 0
(-1625 325);
DISPLAY INVISIBLE (-1625 325);
FORCEPROP 1 LAST LOCATION R796
J 0
(-1580 450);
DISPLAY 0.702128 (-1580 450);
PAINT YELLOW (-1580 450);
FORCEPROP 0 LAST $SEC 1
J 0
(-1575 500);
DISPLAY 0.680851 (-1575 500);
PAINT MONO (-1575 500);
DISPLAY INVISIBLE (-1575 500);
FORCEPROP 0 LAST CDS_SEC 1
J 0
(-1575 500);
DISPLAY 1.021277 (-1575 500);
DISPLAY INVISIBLE (-1575 500);
FORCEPROP 1 LASTPIN (-1625 425) $PN 1
J 0
(-1620 387);
DISPLAY 0.808511 (-1620 387);
PAINT WHITE (-1620 387);
DISPLAY INVISIBLE (-1620 387);
FORCEPROP 1 LASTPIN (-1625 225) $PN 2
J 0
(-1620 235);
DISPLAY 0.808511 (-1620 235);
PAINT WHITE (-1620 235);
DISPLAY INVISIBLE (-1620 235);
FORCEADD Q_CAP..1
(-1625 -75);
FORCEPROP 1 LAST TOLERANCE 10%
J 0
(-1575 -125);
DISPLAY 0.510638 (-1575 -125);
PAINT SKYBLUE (-1575 -125);
FORCEPROP 1 LAST VALUE 0.1UF
J 0
(-1575 -25);
DISPLAY 0.510638 (-1575 -25);
PAINT SKYBLUE (-1575 -25);
FORCEPROP 1 LAST MATERIAL X7R
J 0
(-1575 -175);
DISPLAY 0.510638 (-1575 -175);
PAINT SKYBLUE (-1575 -175);
FORCEPROP 1 LAST PART_NUMBER CH4104K1B00
J 0
(-1575 -275);
DISPLAY 0.510638 (-1575 -275);
PAINT WHITE (-1575 -275);
FORCEPROP 1 LAST VOLTAGE 25V
J 0
(-1575 -75);
DISPLAY 0.510638 (-1575 -75);
PAINT SKYBLUE (-1575 -75);
FORCEPROP 1 LAST PACK_TYPE 0402
J 0
(-1575 -225);
DISPLAY 0.510638 (-1575 -225);
PAINT SKYBLUE (-1575 -225);
FORCEPROP 1 LAST PATH I256
J 0
(-1575 75);
DISPLAY 0.978723 (-1575 75);
PAINT WHITE (-1575 75);
DISPLAY INVISIBLE (-1575 75);
FORCEPROP 2 LAST CDS_LIB pure_quanta
J 0
(-1625 -75);
DISPLAY INVISIBLE (-1625 -75);
FORCEPROP 1 LAST LOCATION C311
J 0
(-1575 25);
DISPLAY 0.702128 (-1575 25);
PAINT YELLOW (-1575 25);
FORCEPROP 1 LASTPIN (-1625 25) $PN 1
J 0
(-1615 5);
DISPLAY 0.808511 (-1615 5);
PAINT WHITE (-1615 5);
FORCEPROP 1 LASTPIN (-1625 -175) $PN 2
J 0
(-1615 -195);
DISPLAY 0.808511 (-1615 -195);
PAINT WHITE (-1615 -195);
FORCEPROP 2 LAST $SEC 1
J 0
(-1575 125);
DISPLAY 0.680851 (-1575 125);
PAINT MONO (-1575 125);
DISPLAY INVISIBLE (-1575 125);
FORCEPROP 0 LAST CDS_SEC 1
J 0
(-1575 125);
DISPLAY 0.680851 (-1575 125);
PAINT MONO (-1575 125);
DISPLAY INVISIBLE (-1575 125);
FORCEADD UNIVERSAL_GND..1
(-1625 -350);
FORCEPROP 3 LASTPIN (-1625 -300) SIG_NAME GND\g
J 0
(-1615 -290);
DISPLAY 0.659574 (-1615 -290);
PAINT MONO (-1615 -290);
DISPLAY INVISIBLE (-1615 -290);
FORCEPROP 1 LAST PATH I257
J 0
(-1550 -350);
DISPLAY 0.872340 (-1550 -350);
PAINT AQUA (-1550 -350);
DISPLAY INVISIBLE (-1550 -350);
FORCEPROP 1 LAST HDL_POWER GND
J 1
(-1641 -384);
DISPLAY 0.702128 (-1641 -384);
PAINT GREEN (-1641 -384);
DISPLAY INVISIBLE (-1641 -384);
FORCEPROP 2 LAST CDS_LIB logical_power
J 0
(-1625 -350);
DISPLAY INVISIBLE (-1625 -350);
FORCEADD OFFPAGE..2
(-600 -1400);
FORCEPROP 2 LAST $XR0 15 
J 0
(-411 -1400);
DISPLAY 0.638298 (-411 -1400);
PAINT MONO (-411 -1400);
FORCEPROP 2 LAST PATH I258
J 0
(-400 -1350);
DISPLAY 1.021277 (-400 -1350);
DISPLAY INVISIBLE (-400 -1350);
FORCEPROP 1 LAST COMMENT_BODY TRUE
J 0
(-645 -1495);
DISPLAY 0.872340 (-645 -1495);
PAINT PEACH (-645 -1495);
DISPLAY INVISIBLE (-645 -1495);
FORCEPROP 1 LAST OFFPAGE TRUE
J 0
(-275 -1525);
DISPLAY 0.872340 (-275 -1525);
PAINT GREEN (-275 -1525);
DISPLAY INVISIBLE (-275 -1525);
FORCEPROP 2 LAST CDS_LIB standard
J 2
(-600 -1400);
DISPLAY INVISIBLE (-600 -1400);
FORCEADD Q_CAP..1
(-1300 -1550);
FORCEPROP 1 LAST PACK_TYPE 0402
J 0
(-1250 -1700);
DISPLAY 0.510638 (-1250 -1700);
PAINT SKYBLUE (-1250 -1700);
FORCEPROP 1 LAST MATERIAL X7R
J 0
(-1250 -1650);
DISPLAY 0.510638 (-1250 -1650);
PAINT SKYBLUE (-1250 -1650);
FORCEPROP 1 LAST PART_NUMBER CH4104K1B00
J 0
(-1250 -1750);
DISPLAY 0.510638 (-1250 -1750);
PAINT WHITE (-1250 -1750);
FORCEPROP 1 LAST TOLERANCE 10%
J 0
(-1250 -1600);
DISPLAY 0.510638 (-1250 -1600);
PAINT SKYBLUE (-1250 -1600);
FORCEPROP 1 LAST VOLTAGE 25V
J 0
(-1250 -1550);
DISPLAY 0.510638 (-1250 -1550);
PAINT SKYBLUE (-1250 -1550);
FORCEPROP 1 LAST VALUE 0.1UF
J 0
(-1250 -1500);
DISPLAY 0.510638 (-1250 -1500);
PAINT SKYBLUE (-1250 -1500);
FORCEPROP 1 LAST PATH I259
J 0
(-1250 -1400);
DISPLAY 0.978723 (-1250 -1400);
PAINT WHITE (-1250 -1400);
DISPLAY INVISIBLE (-1250 -1400);
FORCEPROP 2 LAST CDS_LIB pure_quanta
J 0
(-1300 -1550);
DISPLAY INVISIBLE (-1300 -1550);
FORCEPROP 1 LAST LOCATION C314
J 0
(-1250 -1450);
DISPLAY 0.702128 (-1250 -1450);
PAINT YELLOW (-1250 -1450);
FORCEPROP 1 LASTPIN (-1300 -1450) $PN 1
J 0
(-1290 -1470);
DISPLAY 0.808511 (-1290 -1470);
PAINT WHITE (-1290 -1470);
FORCEPROP 1 LASTPIN (-1300 -1650) $PN 2
J 0
(-1290 -1670);
DISPLAY 0.808511 (-1290 -1670);
PAINT WHITE (-1290 -1670);
FORCEPROP 2 LAST $SEC 1
J 0
(-1250 -1350);
DISPLAY 0.680851 (-1250 -1350);
PAINT MONO (-1250 -1350);
DISPLAY INVISIBLE (-1250 -1350);
FORCEPROP 0 LAST CDS_SEC 1
J 0
(-1250 -1350);
DISPLAY 0.680851 (-1250 -1350);
PAINT MONO (-1250 -1350);
DISPLAY INVISIBLE (-1250 -1350);
FORCEADD OFFPAGE..2
R 2
(-575 1725);
FORCEPROP 2 LAST $XR0 32 
J 0
(-829 1725);
DISPLAY 0.638298 (-829 1725);
PAINT MONO (-829 1725);
FORCEPROP 2 LAST PATH I26
J 0
(-825 1775);
DISPLAY 1.021277 (-825 1775);
DISPLAY INVISIBLE (-825 1775);
FORCEPROP 1 LAST COMMENT_BODY TRUE
J 2
(-530 1630);
DISPLAY 0.872340 (-530 1630);
PAINT PEACH (-530 1630);
DISPLAY INVISIBLE (-530 1630);
FORCEPROP 1 LAST OFFPAGE TRUE
J 2
(-900 1600);
DISPLAY 0.872340 (-900 1600);
PAINT GREEN (-900 1600);
DISPLAY INVISIBLE (-900 1600);
FORCEPROP 2 LAST CDS_LIB standard
J 0
(-575 1725);
DISPLAY INVISIBLE (-575 1725);
FORCEADD Q_RES..2
R 2
(-1500 -1175);
FORCEPROP 1 LAST VALUE 2.87K
J 2
(-1545 -1100);
DISPLAY 0.510638 (-1545 -1100);
PAINT SKYBLUE (-1545 -1100);
FORCEPROP 1 LAST TOLERANCE 1%
J 2
(-1545 -1150);
DISPLAY 0.510638 (-1545 -1150);
PAINT SKYBLUE (-1545 -1150);
FORCEPROP 1 LAST WATTAGE 1/16W
J 2
(-1540 -1200);
DISPLAY 0.510638 (-1540 -1200);
PAINT SKYBLUE (-1540 -1200);
FORCEPROP 1 LAST MATERIAL CHIP
J 2
(-1540 -1250);
DISPLAY 0.510638 (-1540 -1250);
PAINT SKYBLUE (-1540 -1250);
FORCEPROP 1 LAST PACK_TYPE 0402LF
J 2
(-1540 -1350);
DISPLAY 0.510638 (-1540 -1350);
PAINT SKYBLUE (-1540 -1350);
FORCEPROP 1 LAST PART_NUMBER CS22872FB03
J 2
(-1540 -1300);
DISPLAY 0.510638 (-1540 -1300);
PAINT WHITE (-1540 -1300);
FORCEPROP 1 LAST PATH I261
J 2
(-1550 -1000);
DISPLAY 0.978723 (-1550 -1000);
PAINT WHITE (-1550 -1000);
DISPLAY INVISIBLE (-1550 -1000);
FORCEPROP 2 LAST CDS_LIB pure_quanta
J 2
(-1500 -1175);
DISPLAY INVISIBLE (-1500 -1175);
FORCEPROP 1 LAST LOCATION R797
J 2
(-1545 -1050);
DISPLAY 0.702128 (-1545 -1050);
PAINT YELLOW (-1545 -1050);
FORCEPROP 0 LAST $SEC 1
J 0
(-1525 -1000);
DISPLAY 0.680851 (-1525 -1000);
PAINT MONO (-1525 -1000);
DISPLAY INVISIBLE (-1525 -1000);
FORCEPROP 0 LAST CDS_SEC 1
J 0
(-1525 -1000);
DISPLAY 1.021277 (-1525 -1000);
DISPLAY INVISIBLE (-1525 -1000);
FORCEPROP 1 LASTPIN (-1500 -1075) $PN 1
J 2
(-1505 -1113);
DISPLAY 0.808511 (-1505 -1113);
PAINT WHITE (-1505 -1113);
DISPLAY INVISIBLE (-1505 -1113);
FORCEPROP 1 LASTPIN (-1500 -1275) $PN 2
J 2
(-1505 -1265);
DISPLAY 0.808511 (-1505 -1265);
PAINT WHITE (-1505 -1265);
DISPLAY INVISIBLE (-1505 -1265);
FORCEADD Q_RES..2
R 2
(-1500 -1550);
FORCEPROP 1 LAST WATTAGE 1/16W
J 2
(-1540 -1575);
DISPLAY 0.510638 (-1540 -1575);
PAINT SKYBLUE (-1540 -1575);
FORCEPROP 1 LAST TOLERANCE 1%
J 2
(-1545 -1525);
DISPLAY 0.510638 (-1545 -1525);
PAINT SKYBLUE (-1545 -1525);
FORCEPROP 1 LAST MATERIAL CHIP
J 2
(-1540 -1625);
DISPLAY 0.510638 (-1540 -1625);
PAINT SKYBLUE (-1540 -1625);
FORCEPROP 1 LAST PACK_TYPE 0402LF
J 2
(-1540 -1725);
DISPLAY 0.510638 (-1540 -1725);
PAINT SKYBLUE (-1540 -1725);
FORCEPROP 1 LAST PART_NUMBER CS22002FB07
J 2
(-1540 -1675);
DISPLAY 0.510638 (-1540 -1675);
PAINT WHITE (-1540 -1675);
FORCEPROP 1 LAST VALUE 2K
J 2
(-1545 -1475);
DISPLAY 0.510638 (-1545 -1475);
PAINT SKYBLUE (-1545 -1475);
FORCEPROP 1 LAST PATH I262
J 2
(-1550 -1375);
DISPLAY 0.978723 (-1550 -1375);
PAINT WHITE (-1550 -1375);
DISPLAY INVISIBLE (-1550 -1375);
FORCEPROP 2 LAST CDS_LIB pure_quanta
J 2
(-1500 -1550);
DISPLAY INVISIBLE (-1500 -1550);
FORCEPROP 1 LAST LOCATION R798
J 2
(-1545 -1425);
DISPLAY 0.702128 (-1545 -1425);
PAINT YELLOW (-1545 -1425);
FORCEPROP 0 LAST $SEC 1
J 0
(-1525 -1375);
DISPLAY 0.680851 (-1525 -1375);
PAINT MONO (-1525 -1375);
DISPLAY INVISIBLE (-1525 -1375);
FORCEPROP 0 LAST CDS_SEC 1
J 0
(-1525 -1375);
DISPLAY 1.021277 (-1525 -1375);
DISPLAY INVISIBLE (-1525 -1375);
FORCEPROP 1 LASTPIN (-1500 -1450) $PN 1
J 2
(-1505 -1488);
DISPLAY 0.808511 (-1505 -1488);
PAINT WHITE (-1505 -1488);
DISPLAY INVISIBLE (-1505 -1488);
FORCEPROP 1 LASTPIN (-1500 -1650) $PN 2
J 2
(-1505 -1640);
DISPLAY 0.808511 (-1505 -1640);
PAINT WHITE (-1505 -1640);
DISPLAY INVISIBLE (-1505 -1640);
FORCEADD UNIVERSAL_GND..1
(-1500 -1825);
FORCEPROP 3 LASTPIN (-1500 -1775) SIG_NAME GND\g
J 0
(-1490 -1765);
DISPLAY 0.659574 (-1490 -1765);
PAINT MONO (-1490 -1765);
DISPLAY INVISIBLE (-1490 -1765);
FORCEPROP 1 LAST PATH I263
J 0
(-1425 -1825);
DISPLAY 0.872340 (-1425 -1825);
PAINT AQUA (-1425 -1825);
DISPLAY INVISIBLE (-1425 -1825);
FORCEPROP 1 LAST HDL_POWER GND
J 1
(-1516 -1859);
DISPLAY 0.702128 (-1516 -1859);
PAINT GREEN (-1516 -1859);
DISPLAY INVISIBLE (-1516 -1859);
FORCEPROP 2 LAST CDS_LIB logical_power
J 0
(-1500 -1825);
DISPLAY INVISIBLE (-1500 -1825);
FORCEADD UNIVERSAL_POWER..1
(-1500 -975);
FORCEPROP 3 LASTPIN (-1500 -1025) SIG_NAME PGPPA_BMC_AUX\g
J 0
(-1490 -1015);
DISPLAY 0.659574 (-1490 -1015);
PAINT MONO (-1490 -1015);
DISPLAY INVISIBLE (-1490 -1015);
FORCEPROP 1 LAST HDL_POWER PGPPA_BMC_AUX
J 1
(-1500 -925);
DISPLAY 0.702128 (-1500 -925);
PAINT GREEN (-1500 -925);
FORCEPROP 1 LAST PATH I264
J 0
(-1450 -950);
DISPLAY 0.872340 (-1450 -950);
PAINT AQUA (-1450 -950);
DISPLAY INVISIBLE (-1450 -950);
FORCEPROP 2 LAST CDS_LIB logical_power
J 0
(-1500 -975);
DISPLAY INVISIBLE (-1500 -975);
FORCEADD OFFPAGE..1
(-675 2775);
FORCEPROP 2 LAST $XR0 15 
J 0
(-896 2775);
DISPLAY 0.638298 (-896 2775);
PAINT MONO (-896 2775);
FORCEPROP 2 LAST PATH I265
J 0
(-925 2825);
DISPLAY 1.021277 (-925 2825);
DISPLAY INVISIBLE (-925 2825);
FORCEPROP 1 LAST COMMENT_BODY TRUE
J 0
(-550 2675);
DISPLAY 0.872340 (-550 2675);
PAINT PEACH (-550 2675);
DISPLAY INVISIBLE (-550 2675);
FORCEPROP 1 LAST OFFPAGE TRUE
J 0
(-350 2650);
DISPLAY 0.872340 (-350 2650);
PAINT GREEN (-350 2650);
DISPLAY INVISIBLE (-350 2650);
FORCEPROP 2 LAST CDS_LIB standard
J 0
(-675 2775);
DISPLAY INVISIBLE (-675 2775);
FORCEADD OFFPAGE..1
(-675 2725);
FORCEPROP 2 LAST $XR0 15 
J 0
(-896 2725);
DISPLAY 0.638298 (-896 2725);
PAINT MONO (-896 2725);
FORCEPROP 2 LAST PATH I266
J 0
(-875 2775);
DISPLAY 1.021277 (-875 2775);
DISPLAY INVISIBLE (-875 2775);
FORCEPROP 1 LAST COMMENT_BODY TRUE
J 0
(-550 2625);
DISPLAY 0.872340 (-550 2625);
PAINT PEACH (-550 2625);
DISPLAY INVISIBLE (-550 2625);
FORCEPROP 1 LAST OFFPAGE TRUE
J 0
(-350 2600);
DISPLAY 0.872340 (-350 2600);
PAINT GREEN (-350 2600);
DISPLAY INVISIBLE (-350 2600);
FORCEPROP 2 LAST CDS_LIB standard
J 0
(-675 2725);
DISPLAY INVISIBLE (-675 2725);
FORCEADD OFFPAGE..1
(-675 2525);
FORCEPROP 2 LAST $XR0 15 
J 0
(-896 2525);
DISPLAY 0.638298 (-896 2525);
PAINT MONO (-896 2525);
FORCEPROP 2 LAST PATH I267
J 0
(-875 2575);
DISPLAY 1.021277 (-875 2575);
DISPLAY INVISIBLE (-875 2575);
FORCEPROP 1 LAST COMMENT_BODY TRUE
J 0
(-550 2425);
DISPLAY 0.872340 (-550 2425);
PAINT PEACH (-550 2425);
DISPLAY INVISIBLE (-550 2425);
FORCEPROP 1 LAST OFFPAGE TRUE
J 0
(-350 2400);
DISPLAY 0.872340 (-350 2400);
PAINT GREEN (-350 2400);
DISPLAY INVISIBLE (-350 2400);
FORCEPROP 2 LAST CDS_LIB standard
J 0
(-675 2525);
DISPLAY INVISIBLE (-675 2525);
FORCEADD OFFPAGE..2
R 2
(-575 1675);
FORCEPROP 2 LAST $XR0 32 
J 0
(-829 1675);
DISPLAY 0.638298 (-829 1675);
PAINT MONO (-829 1675);
FORCEPROP 2 LAST PATH I27
J 0
(-825 1725);
DISPLAY 1.021277 (-825 1725);
DISPLAY INVISIBLE (-825 1725);
FORCEPROP 1 LAST COMMENT_BODY TRUE
J 2
(-530 1580);
DISPLAY 0.872340 (-530 1580);
PAINT PEACH (-530 1580);
DISPLAY INVISIBLE (-530 1580);
FORCEPROP 1 LAST OFFPAGE TRUE
J 2
(-900 1550);
DISPLAY 0.872340 (-900 1550);
PAINT GREEN (-900 1550);
DISPLAY INVISIBLE (-900 1550);
FORCEPROP 2 LAST CDS_LIB standard
J 0
(-575 1675);
DISPLAY INVISIBLE (-575 1675);
FORCEADD OFFPAGE..1
(-675 2475);
FORCEPROP 2 LAST $XR0 27 
J 0
(-896 2475);
DISPLAY 0.638298 (-896 2475);
PAINT MONO (-896 2475);
FORCEPROP 2 LAST $XR1 35 
J 0
(-986 2475);
DISPLAY 0.638298 (-986 2475);
PAINT MONO (-986 2475);
FORCEPROP 2 LAST PATH I270
J 0
(-625 2550);
DISPLAY 1.021277 (-625 2550);
DISPLAY INVISIBLE (-625 2550);
FORCEPROP 1 LAST COMMENT_BODY TRUE
J 0
(-550 2375);
DISPLAY 0.872340 (-550 2375);
PAINT PEACH (-550 2375);
DISPLAY INVISIBLE (-550 2375);
FORCEPROP 1 LAST OFFPAGE TRUE
J 0
(-350 2350);
DISPLAY 0.872340 (-350 2350);
PAINT GREEN (-350 2350);
DISPLAY INVISIBLE (-350 2350);
FORCEPROP 2 LAST CDS_LIB standard
J 0
(-675 2475);
DISPLAY INVISIBLE (-675 2475);
FORCEADD OFFPAGE..1
(-675 2425);
FORCEPROP 2 LAST $XR0 21 
J 0
(-896 2425);
DISPLAY 0.638298 (-896 2425);
PAINT MONO (-896 2425);
FORCEPROP 2 LAST $XR1 34 
J 0
(-986 2425);
DISPLAY 0.638298 (-986 2425);
PAINT MONO (-986 2425);
FORCEPROP 2 LAST PATH I271
J 0
(-625 2500);
DISPLAY 1.021277 (-625 2500);
DISPLAY INVISIBLE (-625 2500);
FORCEPROP 1 LAST COMMENT_BODY TRUE
J 0
(-550 2325);
DISPLAY 0.872340 (-550 2325);
PAINT GREEN (-550 2325);
DISPLAY INVISIBLE (-550 2325);
FORCEPROP 1 LAST OFFPAGE TRUE
J 0
(-350 2300);
DISPLAY 0.872340 (-350 2300);
DISPLAY INVISIBLE (-350 2300);
FORCEPROP 2 LAST CDS_LIB standard
J 0
(-675 2425);
DISPLAY INVISIBLE (-675 2425);
FORCEADD OFFPAGE..1
(-675 2375);
FORCEPROP 2 LAST $XR0 27 
J 0
(-896 2375);
DISPLAY 0.638298 (-896 2375);
PAINT MONO (-896 2375);
FORCEPROP 2 LAST $XR1 35 
J 0
(-986 2375);
DISPLAY 0.638298 (-986 2375);
PAINT MONO (-986 2375);
FORCEPROP 2 LAST PATH I272
J 0
(-625 2450);
DISPLAY 1.021277 (-625 2450);
DISPLAY INVISIBLE (-625 2450);
FORCEPROP 1 LAST COMMENT_BODY TRUE
J 0
(-550 2275);
DISPLAY 0.872340 (-550 2275);
PAINT PEACH (-550 2275);
DISPLAY INVISIBLE (-550 2275);
FORCEPROP 1 LAST OFFPAGE TRUE
J 0
(-350 2250);
DISPLAY 0.872340 (-350 2250);
PAINT GREEN (-350 2250);
DISPLAY INVISIBLE (-350 2250);
FORCEPROP 2 LAST CDS_LIB standard
J 0
(-675 2375);
DISPLAY INVISIBLE (-675 2375);
FORCEADD OFFPAGE..1
(-675 2325);
FORCEPROP 2 LAST $XR0 35 
J 0
(-896 2325);
DISPLAY 0.638298 (-896 2325);
PAINT MONO (-896 2325);
FORCEPROP 2 LAST PATH I275
J 0
(-625 2400);
DISPLAY 1.021277 (-625 2400);
DISPLAY INVISIBLE (-625 2400);
FORCEPROP 1 LAST COMMENT_BODY TRUE
J 0
(-550 2225);
DISPLAY 0.872340 (-550 2225);
PAINT PEACH (-550 2225);
DISPLAY INVISIBLE (-550 2225);
FORCEPROP 1 LAST OFFPAGE TRUE
J 0
(-350 2200);
DISPLAY 0.872340 (-350 2200);
PAINT GREEN (-350 2200);
DISPLAY INVISIBLE (-350 2200);
FORCEPROP 2 LAST CDS_LIB standard
J 0
(-675 2325);
DISPLAY INVISIBLE (-675 2325);
FORCEADD OFFPAGE..2
R 2
(-575 1775);
FORCEPROP 2 LAST $XR0 32 
J 0
(-829 1775);
DISPLAY 0.638298 (-829 1775);
PAINT MONO (-829 1775);
FORCEPROP 2 LAST PATH I28
J 0
(-825 1825);
DISPLAY 1.021277 (-825 1825);
DISPLAY INVISIBLE (-825 1825);
FORCEPROP 1 LAST COMMENT_BODY TRUE
J 2
(-530 1680);
DISPLAY 0.872340 (-530 1680);
PAINT PEACH (-530 1680);
DISPLAY INVISIBLE (-530 1680);
FORCEPROP 1 LAST OFFPAGE TRUE
J 2
(-900 1650);
DISPLAY 0.872340 (-900 1650);
PAINT GREEN (-900 1650);
DISPLAY INVISIBLE (-900 1650);
FORCEPROP 2 LAST CDS_LIB standard
J 0
(-575 1775);
DISPLAY INVISIBLE (-575 1775);
FORCEADD OFFPAGE..4
(5175 3550);
FORCEPROP 2 LAST $XR0 10 
J 0
(5361 3550);
DISPLAY 0.638298 (5361 3550);
PAINT MONO (5361 3550);
FORCEPROP 2 LAST $XR1 11 
J 0
(5451 3550);
DISPLAY 0.638298 (5451 3550);
PAINT MONO (5451 3550);
FORCEPROP 2 LAST $XR2 50 
J 0
(5541 3550);
DISPLAY 0.638298 (5541 3550);
PAINT MONO (5541 3550);
FORCEPROP 2 LAST $XR3 34 
J 0
(5631 3550);
DISPLAY 0.638298 (5631 3550);
PAINT MONO (5631 3550);
FORCEPROP 2 LAST CDS_LIB standard
J 0
(5175 3550);
DISPLAY INVISIBLE (5175 3550);
FORCEPROP 1 LAST OFFPAGE TRUE
J 0
(5500 3425);
DISPLAY 0.872340 (5500 3425);
PAINT GREEN (5500 3425);
DISPLAY INVISIBLE (5500 3425);
FORCEPROP 1 LAST COMMENT_BODY TRUE
J 0
(5150 3450);
DISPLAY 0.872340 (5150 3450);
PAINT PEACH (5150 3450);
DISPLAY INVISIBLE (5150 3450);
FORCEPROP 2 LAST PATH I287
J 0
(5350 3625);
DISPLAY 1.021277 (5350 3625);
DISPLAY INVISIBLE (5350 3625);
FORCEADD Q_RES..2
(650 -175);
FORCEPROP 1 LAST PART_NUMBER CS42002FB05
J 0
(690 -300);
DISPLAY 0.510638 (690 -300);
PAINT WHITE (690 -300);
FORCEPROP 1 LAST VALUE 200K
J 0
(695 -100);
DISPLAY 0.510638 (695 -100);
PAINT SKYBLUE (695 -100);
FORCEPROP 1 LAST PACK_TYPE 0402LF
J 0
(690 -350);
DISPLAY 0.510638 (690 -350);
PAINT SKYBLUE (690 -350);
FORCEPROP 1 LAST MATERIAL CHIP
J 0
(690 -250);
DISPLAY 0.510638 (690 -250);
PAINT SKYBLUE (690 -250);
FORCEPROP 1 LAST WATTAGE 1/16W
J 0
(690 -200);
DISPLAY 0.510638 (690 -200);
PAINT SKYBLUE (690 -200);
FORCEPROP 1 LAST TOLERANCE 1%
J 0
(695 -150);
DISPLAY 0.510638 (695 -150);
PAINT SKYBLUE (695 -150);
FORCEPROP 1 LAST PATH I289
J 0
(700 0);
DISPLAY 0.978723 (700 0);
PAINT WHITE (700 0);
DISPLAY INVISIBLE (700 0);
FORCEPROP 2 LAST CDS_LIB pure_quanta
J 0
(650 -175);
DISPLAY INVISIBLE (650 -175);
FORCEPROP 1 LAST LOCATION R777
J 0
(695 -50);
DISPLAY 0.702128 (695 -50);
PAINT YELLOW (695 -50);
FORCEPROP 0 LAST $SEC 1
J 0
(700 0);
DISPLAY 0.680851 (700 0);
PAINT MONO (700 0);
DISPLAY INVISIBLE (700 0);
FORCEPROP 0 LAST CDS_SEC 1
J 0
(700 0);
DISPLAY 1.021277 (700 0);
DISPLAY INVISIBLE (700 0);
FORCEPROP 1 LASTPIN (650 -75) $PN 1
J 0
(655 -113);
DISPLAY 0.808511 (655 -113);
PAINT WHITE (655 -113);
DISPLAY INVISIBLE (655 -113);
FORCEPROP 1 LASTPIN (650 -275) $PN 2
J 0
(655 -265);
DISPLAY 0.808511 (655 -265);
PAINT WHITE (655 -265);
DISPLAY INVISIBLE (655 -265);
FORCEADD OFFPAGE..2
R 2
(-575 1825);
FORCEPROP 2 LAST $XR0 32 
J 0
(-829 1825);
DISPLAY 0.638298 (-829 1825);
PAINT MONO (-829 1825);
FORCEPROP 2 LAST PATH I29
J 0
(-825 1875);
DISPLAY 1.021277 (-825 1875);
DISPLAY INVISIBLE (-825 1875);
FORCEPROP 1 LAST COMMENT_BODY TRUE
J 2
(-530 1730);
DISPLAY 0.872340 (-530 1730);
PAINT PEACH (-530 1730);
DISPLAY INVISIBLE (-530 1730);
FORCEPROP 1 LAST OFFPAGE TRUE
J 2
(-900 1700);
DISPLAY 0.872340 (-900 1700);
PAINT GREEN (-900 1700);
DISPLAY INVISIBLE (-900 1700);
FORCEPROP 2 LAST CDS_LIB standard
J 0
(-575 1825);
DISPLAY INVISIBLE (-575 1825);
FORCEADD OFFPAGE..1
(-775 3475);
FORCEPROP 2 LAST $XR0 34 
J 0
(-996 3475);
DISPLAY 0.638298 (-996 3475);
PAINT MONO (-996 3475);
FORCEPROP 2 LAST CDS_LIB standard
J 0
(-775 3475);
DISPLAY INVISIBLE (-775 3475);
FORCEPROP 1 LAST OFFPAGE TRUE
J 0
(-450 3350);
DISPLAY 0.872340 (-450 3350);
PAINT GREEN (-450 3350);
DISPLAY INVISIBLE (-450 3350);
FORCEPROP 1 LAST COMMENT_BODY TRUE
J 0
(-650 3375);
DISPLAY 0.872340 (-650 3375);
PAINT PEACH (-650 3375);
DISPLAY INVISIBLE (-650 3375);
FORCEPROP 2 LAST PATH I292
J 0
(-975 3525);
DISPLAY 1.021277 (-975 3525);
DISPLAY INVISIBLE (-975 3525);
FORCEADD OFFPAGE..1
(-775 3425);
FORCEPROP 2 LAST $XR0 34 
J 0
(-996 3425);
DISPLAY 0.638298 (-996 3425);
PAINT MONO (-996 3425);
FORCEPROP 2 LAST CDS_LIB standard
J 0
(-775 3425);
DISPLAY INVISIBLE (-775 3425);
FORCEPROP 1 LAST OFFPAGE TRUE
J 0
(-450 3300);
DISPLAY 0.872340 (-450 3300);
PAINT GREEN (-450 3300);
DISPLAY INVISIBLE (-450 3300);
FORCEPROP 1 LAST COMMENT_BODY TRUE
J 0
(-650 3325);
DISPLAY 0.872340 (-650 3325);
PAINT PEACH (-650 3325);
DISPLAY INVISIBLE (-650 3325);
FORCEPROP 2 LAST PATH I293
J 0
(-975 3475);
DISPLAY 1.021277 (-975 3475);
DISPLAY INVISIBLE (-975 3475);
FORCEADD OFFPAGE..5
(-775 3375);
FORCEPROP 2 LAST $XR0 34 
J 0
(-1029 3375);
DISPLAY 0.638298 (-1029 3375);
PAINT MONO (-1029 3375);
FORCEPROP 2 LAST CDS_LIB standard
J 0
(-775 3375);
DISPLAY INVISIBLE (-775 3375);
FORCEPROP 1 LAST OFFPAGE TRUE
J 0
(-450 3250);
DISPLAY 0.872340 (-450 3250);
PAINT GREEN (-450 3250);
DISPLAY INVISIBLE (-450 3250);
FORCEPROP 1 LAST COMMENT_BODY TRUE
J 0
(-675 3300);
DISPLAY 0.872340 (-675 3300);
PAINT PEACH (-675 3300);
DISPLAY INVISIBLE (-675 3300);
FORCEPROP 2 LAST PATH I294
J 0
(-975 3425);
DISPLAY 1.021277 (-975 3425);
DISPLAY INVISIBLE (-975 3425);
FORCEADD OFFPAGE..1
(-775 3125);
FORCEPROP 2 LAST $XR0 34 
J 0
(-996 3125);
DISPLAY 0.638298 (-996 3125);
PAINT MONO (-996 3125);
FORCEPROP 2 LAST CDS_LIB standard
J 0
(-775 3125);
DISPLAY INVISIBLE (-775 3125);
FORCEPROP 1 LAST OFFPAGE TRUE
J 0
(-450 3000);
DISPLAY 0.872340 (-450 3000);
PAINT GREEN (-450 3000);
DISPLAY INVISIBLE (-450 3000);
FORCEPROP 1 LAST COMMENT_BODY TRUE
J 0
(-650 3025);
DISPLAY 0.872340 (-650 3025);
PAINT PEACH (-650 3025);
DISPLAY INVISIBLE (-650 3025);
FORCEPROP 2 LAST PATH I299
J 0
(-1000 3175);
DISPLAY 1.021277 (-1000 3175);
DISPLAY INVISIBLE (-1000 3175);
FORCEADD UNIVERSAL_POWER..1
(2050 -300);
FORCEPROP 3 LASTPIN (2050 -350) SIG_NAME P3V3_AUX\g
J 0
(2060 -340);
DISPLAY 0.659574 (2060 -340);
PAINT MONO (2060 -340);
DISPLAY INVISIBLE (2060 -340);
FORCEPROP 1 LAST HDL_POWER P3V3_AUX
J 1
(2050 -250);
DISPLAY 0.702128 (2050 -250);
PAINT GREEN (2050 -250);
FORCEPROP 1 LAST PATH I3
J 0
(2100 -275);
DISPLAY 0.872340 (2100 -275);
PAINT AQUA (2100 -275);
DISPLAY INVISIBLE (2100 -275);
FORCEPROP 2 LAST CDS_LIB logical_power
J 0
(2050 -300);
DISPLAY INVISIBLE (2050 -300);
FORCEADD OFFPAGE..1
(-775 3175);
FORCEPROP 2 LAST $XR0 34 
J 0
(-996 3175);
DISPLAY 0.638298 (-996 3175);
PAINT MONO (-996 3175);
FORCEPROP 2 LAST CDS_LIB standard
J 0
(-775 3175);
DISPLAY INVISIBLE (-775 3175);
FORCEPROP 1 LAST OFFPAGE TRUE
J 0
(-450 3050);
DISPLAY 0.872340 (-450 3050);
PAINT GREEN (-450 3050);
DISPLAY INVISIBLE (-450 3050);
FORCEPROP 1 LAST COMMENT_BODY TRUE
J 0
(-650 3075);
DISPLAY 0.872340 (-650 3075);
PAINT PEACH (-650 3075);
DISPLAY INVISIBLE (-650 3075);
FORCEPROP 2 LAST PATH I300
J 0
(-725 3250);
DISPLAY 1.021277 (-725 3250);
DISPLAY INVISIBLE (-725 3250);
FORCEADD OFFPAGE..1
(-775 3225);
FORCEPROP 2 LAST $XR0 34 
J 0
(-996 3225);
DISPLAY 0.638298 (-996 3225);
PAINT MONO (-996 3225);
FORCEPROP 2 LAST CDS_LIB standard
J 0
(-775 3225);
DISPLAY INVISIBLE (-775 3225);
FORCEPROP 1 LAST OFFPAGE TRUE
J 0
(-450 3100);
DISPLAY 0.872340 (-450 3100);
PAINT GREEN (-450 3100);
DISPLAY INVISIBLE (-450 3100);
FORCEPROP 1 LAST COMMENT_BODY TRUE
J 0
(-650 3125);
DISPLAY 0.872340 (-650 3125);
PAINT PEACH (-650 3125);
DISPLAY INVISIBLE (-650 3125);
FORCEPROP 2 LAST PATH I301
J 0
(-725 3300);
DISPLAY 1.021277 (-725 3300);
DISPLAY INVISIBLE (-725 3300);
FORCEADD OFFPAGE..1
(-775 3275);
FORCEPROP 2 LAST $XR0 34 
J 0
(-996 3275);
DISPLAY 0.638298 (-996 3275);
PAINT MONO (-996 3275);
FORCEPROP 2 LAST CDS_LIB standard
J 0
(-775 3275);
DISPLAY INVISIBLE (-775 3275);
FORCEPROP 1 LAST OFFPAGE TRUE
J 0
(-450 3150);
DISPLAY 0.872340 (-450 3150);
PAINT GREEN (-450 3150);
DISPLAY INVISIBLE (-450 3150);
FORCEPROP 1 LAST COMMENT_BODY TRUE
J 0
(-650 3175);
DISPLAY 0.872340 (-650 3175);
PAINT PEACH (-650 3175);
DISPLAY INVISIBLE (-650 3175);
FORCEPROP 2 LAST PATH I302
J 0
(-725 3350);
DISPLAY 1.021277 (-725 3350);
DISPLAY INVISIBLE (-725 3350);
FORCEADD OFFPAGE..1
(-775 3325);
FORCEPROP 2 LAST $XR0 34 
J 0
(-1026 3325);
DISPLAY 0.638298 (-1026 3325);
PAINT MONO (-1026 3325);
FORCEPROP 2 LAST CDS_LIB standard
J 0
(-775 3325);
DISPLAY INVISIBLE (-775 3325);
FORCEPROP 1 LAST OFFPAGE TRUE
J 0
(-450 3200);
DISPLAY 0.872340 (-450 3200);
PAINT GREEN (-450 3200);
DISPLAY INVISIBLE (-450 3200);
FORCEPROP 1 LAST COMMENT_BODY TRUE
J 0
(-650 3225);
DISPLAY 0.872340 (-650 3225);
PAINT PEACH (-650 3225);
DISPLAY INVISIBLE (-650 3225);
FORCEPROP 2 LAST PATH I303
J 0
(-725 3400);
DISPLAY 1.021277 (-725 3400);
DISPLAY INVISIBLE (-725 3400);
FORCEADD OFFPAGE..4
(3375 3775);
FORCEPROP 2 LAST $XR0 34 
J 0
(3561 3775);
DISPLAY 0.638298 (3561 3775);
PAINT MONO (3561 3775);
FORCEPROP 2 LAST PATH I306
J 0
(3575 3850);
DISPLAY 1.021277 (3575 3850);
DISPLAY INVISIBLE (3575 3850);
FORCEPROP 1 LAST COMMENT_BODY TRUE
J 0
(3350 3675);
DISPLAY 0.872340 (3350 3675);
PAINT PEACH (3350 3675);
DISPLAY INVISIBLE (3350 3675);
FORCEPROP 1 LAST OFFPAGE TRUE
J 0
(3700 3650);
DISPLAY 0.872340 (3700 3650);
PAINT GREEN (3700 3650);
DISPLAY INVISIBLE (3700 3650);
FORCEPROP 2 LAST CDS_LIB standard
J 0
(3375 3775);
DISPLAY INVISIBLE (3375 3775);
FORCEADD OFFPAGE..2
(3375 3525);
FORCEPROP 2 LAST $XR0 35 
J 0
(3564 3525);
DISPLAY 0.638298 (3564 3525);
PAINT MONO (3564 3525);
FORCEPROP 2 LAST PATH I309
J 0
(3575 3600);
DISPLAY 1.021277 (3575 3600);
DISPLAY INVISIBLE (3575 3600);
FORCEPROP 1 LAST COMMENT_BODY TRUE
J 0
(3330 3430);
DISPLAY 0.872340 (3330 3430);
PAINT PEACH (3330 3430);
DISPLAY INVISIBLE (3330 3430);
FORCEPROP 1 LAST OFFPAGE TRUE
J 0
(3700 3400);
DISPLAY 0.872340 (3700 3400);
PAINT GREEN (3700 3400);
DISPLAY INVISIBLE (3700 3400);
FORCEPROP 2 LAST CDS_LIB standard
J 0
(3375 3525);
DISPLAY INVISIBLE (3375 3525);
FORCEADD UNIVERSAL_POWER..1
(4125 -500);
FORCEPROP 3 LASTPIN (4125 -550) SIG_NAME P1V8_AUX\g
J 0
(4135 -540);
DISPLAY 0.659574 (4135 -540);
PAINT MONO (4135 -540);
DISPLAY INVISIBLE (4135 -540);
FORCEPROP 1 LAST HDL_POWER P1V8_AUX
J 1
(4125 -450);
DISPLAY 0.702128 (4125 -450);
PAINT GREEN (4125 -450);
FORCEPROP 1 LAST PATH I31
J 0
(4175 -475);
DISPLAY 0.872340 (4175 -475);
PAINT AQUA (4175 -475);
DISPLAY INVISIBLE (4175 -475);
FORCEPROP 2 LAST CDS_LIB logical_power
J 0
(4125 -500);
DISPLAY INVISIBLE (4125 -500);
FORCEADD OFFPAGE..4
(3475 3225);
FORCEPROP 2 LAST $XR0 35 
J 0
(3661 3225);
DISPLAY 0.638298 (3661 3225);
PAINT MONO (3661 3225);
FORCEPROP 2 LAST PATH I311
J 0
(3675 3300);
DISPLAY 1.021277 (3675 3300);
DISPLAY INVISIBLE (3675 3300);
FORCEPROP 1 LAST COMMENT_BODY TRUE
J 0
(3450 3125);
DISPLAY 0.872340 (3450 3125);
PAINT PEACH (3450 3125);
DISPLAY INVISIBLE (3450 3125);
FORCEPROP 1 LAST OFFPAGE TRUE
J 0
(3800 3100);
DISPLAY 0.872340 (3800 3100);
PAINT GREEN (3800 3100);
DISPLAY INVISIBLE (3800 3100);
FORCEPROP 2 LAST CDS_LIB standard
J 0
(3475 3225);
DISPLAY INVISIBLE (3475 3225);
FORCEADD OFFPAGE..4
(3475 3175);
FORCEPROP 2 LAST $XR0 35 
J 0
(3661 3175);
DISPLAY 0.638298 (3661 3175);
PAINT MONO (3661 3175);
FORCEPROP 2 LAST PATH I312
J 0
(3675 3250);
DISPLAY 1.021277 (3675 3250);
DISPLAY INVISIBLE (3675 3250);
FORCEPROP 1 LAST COMMENT_BODY TRUE
J 0
(3450 3075);
DISPLAY 0.872340 (3450 3075);
PAINT PEACH (3450 3075);
DISPLAY INVISIBLE (3450 3075);
FORCEPROP 1 LAST OFFPAGE TRUE
J 0
(3800 3050);
DISPLAY 0.872340 (3800 3050);
PAINT GREEN (3800 3050);
DISPLAY INVISIBLE (3800 3050);
FORCEPROP 2 LAST CDS_LIB standard
J 0
(3475 3175);
DISPLAY INVISIBLE (3475 3175);
FORCEADD OFFPAGE..4
(5175 3475);
FORCEPROP 2 LAST $XR0 35 
J 0
(5361 3475);
DISPLAY 0.638298 (5361 3475);
PAINT MONO (5361 3475);
FORCEPROP 2 LAST CDS_LIB standard
J 0
(5175 3475);
DISPLAY INVISIBLE (5175 3475);
FORCEPROP 1 LAST OFFPAGE TRUE
J 0
(5500 3350);
DISPLAY 0.872340 (5500 3350);
PAINT GREEN (5500 3350);
DISPLAY INVISIBLE (5500 3350);
FORCEPROP 1 LAST COMMENT_BODY TRUE
J 0
(5150 3375);
DISPLAY 0.872340 (5150 3375);
PAINT PEACH (5150 3375);
DISPLAY INVISIBLE (5150 3375);
FORCEPROP 2 LAST PATH I313
J 0
(5350 3550);
DISPLAY 1.021277 (5350 3550);
DISPLAY INVISIBLE (5350 3550);
FORCEADD OFFPAGE..4
(3375 3675);
FORCEPROP 2 LAST $XR0 35 
J 0
(3561 3675);
DISPLAY 0.638298 (3561 3675);
PAINT MONO (3561 3675);
FORCEPROP 2 LAST $XR1 42 
J 0
(3651 3675);
DISPLAY 0.638298 (3651 3675);
PAINT MONO (3651 3675);
FORCEPROP 2 LAST PATH I315
J 0
(3550 3750);
DISPLAY 1.021277 (3550 3750);
DISPLAY INVISIBLE (3550 3750);
FORCEPROP 1 LAST COMMENT_BODY TRUE
J 0
(3350 3575);
DISPLAY 0.872340 (3350 3575);
PAINT PEACH (3350 3575);
DISPLAY INVISIBLE (3350 3575);
FORCEPROP 1 LAST OFFPAGE TRUE
J 0
(3700 3550);
DISPLAY 0.872340 (3700 3550);
PAINT GREEN (3700 3550);
DISPLAY INVISIBLE (3700 3550);
FORCEPROP 2 LAST CDS_LIB standard
J 0
(3375 3675);
DISPLAY INVISIBLE (3375 3675);
FORCEADD OFFPAGE..4
(3375 3575);
FORCEPROP 2 LAST $XR0 34 
J 0
(3561 3575);
DISPLAY 0.638298 (3561 3575);
PAINT MONO (3561 3575);
FORCEPROP 2 LAST PATH I316
J 0
(3550 3650);
DISPLAY 1.021277 (3550 3650);
DISPLAY INVISIBLE (3550 3650);
FORCEPROP 1 LAST COMMENT_BODY TRUE
J 0
(3350 3475);
DISPLAY 0.872340 (3350 3475);
PAINT PEACH (3350 3475);
DISPLAY INVISIBLE (3350 3475);
FORCEPROP 1 LAST OFFPAGE TRUE
J 0
(3700 3450);
DISPLAY 0.872340 (3700 3450);
PAINT GREEN (3700 3450);
DISPLAY INVISIBLE (3700 3450);
FORCEPROP 2 LAST CDS_LIB standard
J 0
(3375 3575);
DISPLAY INVISIBLE (3375 3575);
FORCEADD OFFPAGE..4
(3375 3875);
FORCEPROP 2 LAST $XR0 35 
J 0
(3561 3875);
DISPLAY 0.638298 (3561 3875);
PAINT MONO (3561 3875);
FORCEPROP 2 LAST PATH I317
J 0
(3575 3925);
DISPLAY 1.021277 (3575 3925);
DISPLAY INVISIBLE (3575 3925);
FORCEPROP 1 LAST COMMENT_BODY TRUE
J 0
(3350 3775);
DISPLAY 0.872340 (3350 3775);
PAINT PEACH (3350 3775);
DISPLAY INVISIBLE (3350 3775);
FORCEPROP 1 LAST OFFPAGE TRUE
J 0
(3700 3750);
DISPLAY 0.872340 (3700 3750);
PAINT GREEN (3700 3750);
DISPLAY INVISIBLE (3700 3750);
FORCEPROP 2 LAST CDS_LIB standard
J 0
(3375 3875);
DISPLAY INVISIBLE (3375 3875);
FORCEADD Q_RES..1
(4125 3275);
FORCEPROP 1 LAST MATERIAL CHIP
J 0
(4275 3275);
DISPLAY 0.510638 (4275 3275);
PAINT SKYBLUE (4275 3275);
FORCEPROP 1 LAST VALUE 0
J 2
(4225 3275);
DISPLAY 0.510638 (4225 3275);
PAINT SKYBLUE (4225 3275);
FORCEPROP 1 LAST PART_NUMBER CS00002JB13
J 0
(4025 3350);
DISPLAY 0.510638 (4025 3350);
PAINT WHITE (4025 3350);
DISPLAY INVISIBLE (4025 3350);
FORCEPROP 1 LAST PACK_TYPE 0402LF
J 0
(4100 3325);
DISPLAY 0.510638 (4100 3325);
PAINT SKYBLUE (4100 3325);
DISPLAY INVISIBLE (4100 3325);
FORCEPROP 1 LAST WATTAGE 1/16W
J 2
(4475 3375);
DISPLAY 0.510638 (4475 3375);
PAINT SKYBLUE (4475 3375);
DISPLAY INVISIBLE (4475 3375);
FORCEPROP 1 LAST PATH I318
J 0
(4075 3425);
DISPLAY 0.978723 (4075 3425);
PAINT WHITE (4075 3425);
DISPLAY INVISIBLE (4075 3425);
FORCEPROP 1 LAST TOLERANCE 5%
J 0
(4050 3375);
DISPLAY 0.510638 (4050 3375);
PAINT SKYBLUE (4050 3375);
DISPLAY INVISIBLE (4050 3375);
FORCEPROP 2 LAST CDS_LIB pure_quanta
J 0
(4125 3275);
DISPLAY INVISIBLE (4125 3275);
FORCEPROP 1 LAST LOCATION R316
J 0
(3925 3275);
DISPLAY 0.702128 (3925 3275);
PAINT YELLOW (3925 3275);
FORCEPROP 0 LAST $SEC 1
J 0
(3975 3325);
DISPLAY 0.680851 (3975 3325);
PAINT MONO (3975 3325);
DISPLAY INVISIBLE (3975 3325);
FORCEPROP 0 LAST CDS_SEC 1
J 0
(3975 3325);
DISPLAY 1.021277 (3975 3325);
DISPLAY INVISIBLE (3975 3325);
FORCEPROP 1 LASTPIN (4025 3275) $PN 1
J 0
(4037 3287);
DISPLAY 0.808511 (4037 3287);
PAINT WHITE (4037 3287);
DISPLAY INVISIBLE (4037 3287);
FORCEPROP 1 LASTPIN (4225 3275) $PN 2
J 0
(4187 3287);
DISPLAY 0.808511 (4187 3287);
PAINT WHITE (4187 3287);
DISPLAY INVISIBLE (4187 3287);
FORCEADD OFFPAGE..2
(5200 3275);
FORCEPROP 2 LAST $XR1 49 
J 0
(5479 3275);
DISPLAY 0.638298 (5479 3275);
PAINT MONO (5479 3275);
FORCEPROP 2 LAST $XR0 35 
J 0
(5389 3275);
DISPLAY 0.638298 (5389 3275);
PAINT MONO (5389 3275);
FORCEPROP 2 LAST PATH I319
J 0
(5500 3325);
DISPLAY 0.680851 (5500 3325);
DISPLAY INVISIBLE (5500 3325);
FORCEPROP 1 LAST COMMENT_BODY TRUE
J 0
(5155 3180);
DISPLAY 0.872340 (5155 3180);
PAINT PEACH (5155 3180);
DISPLAY INVISIBLE (5155 3180);
FORCEPROP 1 LAST OFFPAGE TRUE
J 0
(5525 3150);
DISPLAY 0.872340 (5525 3150);
PAINT GREEN (5525 3150);
DISPLAY INVISIBLE (5525 3150);
FORCEPROP 2 LAST CDS_LIB standard
J 0
(5200 3275);
DISPLAY INVISIBLE (5200 3275);
FORCEADD Q_RES..1
(4700 -650);
FORCEPROP 1 LAST VALUE 0
J 2
(4900 -650);
DISPLAY 0.510638 (4900 -650);
PAINT SKYBLUE (4900 -650);
FORCEPROP 1 LAST MATERIAL EMPTY
J 0
(4975 -650);
DISPLAY 0.510638 (4975 -650);
PAINT RED (4975 -650);
FORCEPROP 1 LAST PART_NUMBER CS00002JB13
J 0
(4700 -475);
DISPLAY 0.510638 (4700 -475);
PAINT WHITE (4700 -475);
DISPLAY INVISIBLE (4700 -475);
FORCEPROP 1 LAST PACK_TYPE 0402LF
J 0
(4900 -550);
DISPLAY 0.510638 (4900 -550);
PAINT SKYBLUE (4900 -550);
DISPLAY INVISIBLE (4900 -550);
FORCEPROP 1 LAST WATTAGE 1/16W
J 2
(4875 -550);
DISPLAY 0.510638 (4875 -550);
PAINT SKYBLUE (4875 -550);
DISPLAY INVISIBLE (4875 -550);
FORCEPROP 1 LAST PATH I32
J 0
(4650 -500);
DISPLAY 0.978723 (4650 -500);
PAINT WHITE (4650 -500);
DISPLAY INVISIBLE (4650 -500);
FORCEPROP 1 LAST TOLERANCE 5%
J 0
(5200 -550);
DISPLAY 0.510638 (5200 -550);
PAINT SKYBLUE (5200 -550);
DISPLAY INVISIBLE (5200 -550);
FORCEPROP 2 LAST CDS_LIB pure_quanta
J 0
(4700 -650);
DISPLAY INVISIBLE (4700 -650);
FORCEPROP 1 LAST LOCATION R214
J 0
(4425 -650);
DISPLAY 0.702128 (4425 -650);
PAINT YELLOW (4425 -650);
FORCEPROP 1 LASTPIN (4600 -650) $PN 1
J 0
(4612 -638);
DISPLAY 0.808511 (4612 -638);
PAINT WHITE (4612 -638);
FORCEPROP 1 LASTPIN (4800 -650) $PN 2
J 0
(4762 -638);
DISPLAY 0.808511 (4762 -638);
PAINT WHITE (4762 -638);
FORCEPROP 2 LAST $SEC 1
J 0
(4650 -450);
DISPLAY 0.680851 (4650 -450);
PAINT MONO (4650 -450);
DISPLAY INVISIBLE (4650 -450);
FORCEPROP 0 LAST CDS_SEC 1
J 0
(4650 -450);
DISPLAY 0.680851 (4650 -450);
PAINT MONO (4650 -450);
DISPLAY INVISIBLE (4650 -450);
FORCEADD Q_RES..1
(-1300 2625);
FORCEPROP 1 LAST VALUE 33.2
J 0
(-1200 2625);
DISPLAY 0.510638 (-1200 2625);
PAINT SKYBLUE (-1200 2625);
FORCEPROP 1 LAST MATERIAL CHIP
J 0
(-1100 2625);
DISPLAY 0.510638 (-1100 2625);
PAINT SKYBLUE (-1100 2625);
FORCEPROP 1 LAST TOLERANCE 1%
J 0
(-1175 2625);
DISPLAY 0.510638 (-1175 2625);
PAINT SKYBLUE (-1175 2625);
DISPLAY INVISIBLE (-1175 2625);
FORCEPROP 1 LAST PART_NUMBER CS03322FB03
J 0
(-1350 2725);
DISPLAY 0.510638 (-1350 2725);
PAINT WHITE (-1350 2725);
DISPLAY INVISIBLE (-1350 2725);
FORCEPROP 1 LAST PACK_TYPE 0402LF
J 0
(-1050 2475);
DISPLAY 0.510638 (-1050 2475);
PAINT SKYBLUE (-1050 2475);
DISPLAY INVISIBLE (-1050 2475);
FORCEPROP 1 LAST WATTAGE 1/16W
J 2
(-1325 2475);
DISPLAY 0.510638 (-1325 2475);
PAINT SKYBLUE (-1325 2475);
DISPLAY INVISIBLE (-1325 2475);
FORCEPROP 1 LAST PATH I320
J 0
(-1350 2775);
DISPLAY 0.978723 (-1350 2775);
PAINT WHITE (-1350 2775);
DISPLAY INVISIBLE (-1350 2775);
FORCEPROP 2 LAST CDS_LIB pure_quanta
J 0
(-1300 2625);
DISPLAY INVISIBLE (-1300 2625);
FORCEPROP 1 LAST LOCATION R448
J 0
(-1500 2625);
DISPLAY 0.702128 (-1500 2625);
PAINT YELLOW (-1500 2625);
FORCEPROP 1 LASTPIN (-1400 2625) $PN 1
J 0
(-1388 2637);
DISPLAY 0.808511 (-1388 2637);
PAINT WHITE (-1388 2637);
FORCEPROP 1 LASTPIN (-1200 2625) $PN 2
J 0
(-1238 2637);
DISPLAY 0.808511 (-1238 2637);
PAINT WHITE (-1238 2637);
FORCEPROP 2 LAST $SEC 1
J 0
(-1350 2825);
DISPLAY 0.680851 (-1350 2825);
PAINT MONO (-1350 2825);
DISPLAY INVISIBLE (-1350 2825);
FORCEPROP 0 LAST CDS_SEC 1
J 0
(-1350 2825);
DISPLAY 0.680851 (-1350 2825);
PAINT MONO (-1350 2825);
DISPLAY INVISIBLE (-1350 2825);
FORCEADD Q_RES..1
(-1300 2575);
FORCEPROP 1 LAST MATERIAL CHIP
J 0
(-1100 2575);
DISPLAY 0.510638 (-1100 2575);
PAINT SKYBLUE (-1100 2575);
FORCEPROP 1 LAST VALUE 33.2
J 0
(-1200 2575);
DISPLAY 0.510638 (-1200 2575);
PAINT SKYBLUE (-1200 2575);
FORCEPROP 1 LAST TOLERANCE 1%
J 0
(-1175 2575);
DISPLAY 0.510638 (-1175 2575);
PAINT SKYBLUE (-1175 2575);
DISPLAY INVISIBLE (-1175 2575);
FORCEPROP 1 LAST PART_NUMBER CS03322FB03
J 0
(-1350 2675);
DISPLAY 0.510638 (-1350 2675);
PAINT WHITE (-1350 2675);
DISPLAY INVISIBLE (-1350 2675);
FORCEPROP 1 LAST PACK_TYPE 0402LF
J 0
(-1050 2425);
DISPLAY 0.510638 (-1050 2425);
PAINT SKYBLUE (-1050 2425);
DISPLAY INVISIBLE (-1050 2425);
FORCEPROP 1 LAST WATTAGE 1/16W
J 2
(-1325 2425);
DISPLAY 0.510638 (-1325 2425);
PAINT SKYBLUE (-1325 2425);
DISPLAY INVISIBLE (-1325 2425);
FORCEPROP 1 LAST PATH I321
J 0
(-1350 2725);
DISPLAY 0.978723 (-1350 2725);
PAINT WHITE (-1350 2725);
DISPLAY INVISIBLE (-1350 2725);
FORCEPROP 2 LAST CDS_LIB pure_quanta
J 0
(-1300 2575);
DISPLAY INVISIBLE (-1300 2575);
FORCEPROP 1 LAST LOCATION R449
J 0
(-1500 2575);
DISPLAY 0.702128 (-1500 2575);
PAINT YELLOW (-1500 2575);
FORCEPROP 1 LASTPIN (-1400 2575) $PN 1
J 0
(-1388 2587);
DISPLAY 0.808511 (-1388 2587);
PAINT WHITE (-1388 2587);
FORCEPROP 1 LASTPIN (-1200 2575) $PN 2
J 0
(-1238 2587);
DISPLAY 0.808511 (-1238 2587);
PAINT WHITE (-1238 2587);
FORCEPROP 0 LAST $SEC 1
J 0
(-1350 2675);
DISPLAY 0.680851 (-1350 2675);
PAINT MONO (-1350 2675);
DISPLAY INVISIBLE (-1350 2675);
FORCEPROP 0 LAST CDS_SEC 1
J 0
(-1350 2675);
DISPLAY 0.680851 (-1350 2675);
DISPLAY INVISIBLE (-1350 2675);
FORCEADD OFFPAGE..6
(-2275 2625);
FORCEPROP 2 LAST $XR1 35 
J 0
(-2614 2625);
DISPLAY 0.638298 (-2614 2625);
PAINT MONO (-2614 2625);
FORCEPROP 2 LAST $XR0 27 
J 0
(-2524 2625);
DISPLAY 0.638298 (-2524 2625);
PAINT MONO (-2524 2625);
FORCEPROP 2 LAST PATH I322
J 0
(-2225 2700);
DISPLAY 0.680851 (-2225 2700);
DISPLAY INVISIBLE (-2225 2700);
FORCEPROP 1 LAST COMMENT_BODY TRUE
J 0
(-2175 2550);
DISPLAY 0.872340 (-2175 2550);
PAINT GREEN (-2175 2550);
DISPLAY INVISIBLE (-2175 2550);
FORCEPROP 1 LAST OFFPAGE TRUE
J 0
(-1950 2500);
DISPLAY 0.872340 (-1950 2500);
DISPLAY INVISIBLE (-1950 2500);
FORCEPROP 2 LAST CDS_LIB standard
J 0
(-2275 2625);
DISPLAY INVISIBLE (-2275 2625);
FORCEADD OFFPAGE..6
(-2275 2575);
FORCEPROP 2 LAST $XR1 35 
J 0
(-2614 2575);
DISPLAY 0.638298 (-2614 2575);
PAINT MONO (-2614 2575);
FORCEPROP 2 LAST $XR0 27 
J 0
(-2524 2575);
DISPLAY 0.638298 (-2524 2575);
PAINT MONO (-2524 2575);
FORCEPROP 1 LAST OFFPAGE TRUE
J 0
(-1950 2450);
DISPLAY 0.872340 (-1950 2450);
DISPLAY INVISIBLE (-1950 2450);
FORCEPROP 1 LAST COMMENT_BODY TRUE
J 0
(-2175 2500);
DISPLAY 0.872340 (-2175 2500);
PAINT GREEN (-2175 2500);
DISPLAY INVISIBLE (-2175 2500);
FORCEPROP 2 LAST PATH I323
J 0
(-2225 2650);
DISPLAY 0.680851 (-2225 2650);
DISPLAY INVISIBLE (-2225 2650);
FORCEPROP 2 LAST CDS_LIB standard
J 0
(-2275 2575);
DISPLAY INVISIBLE (-2275 2575);
FORCEADD Q_RES..1
(-825 3525);
FORCEPROP 1 LAST MATERIAL CHIP
J 0
(-600 3525);
DISPLAY 0.510638 (-600 3525);
PAINT SKYBLUE (-600 3525);
FORCEPROP 1 LAST VALUE 33.2
J 0
(-725 3525);
DISPLAY 0.510638 (-725 3525);
PAINT SKYBLUE (-725 3525);
FORCEPROP 1 LAST TOLERANCE 1%
J 0
(-700 3525);
DISPLAY 0.510638 (-700 3525);
PAINT SKYBLUE (-700 3525);
DISPLAY INVISIBLE (-700 3525);
FORCEPROP 1 LAST PART_NUMBER CS03322FB03
J 0
(-875 3625);
DISPLAY 0.510638 (-875 3625);
PAINT WHITE (-875 3625);
DISPLAY INVISIBLE (-875 3625);
FORCEPROP 1 LAST WATTAGE 1/16W
J 2
(-850 3375);
DISPLAY 0.510638 (-850 3375);
PAINT SKYBLUE (-850 3375);
DISPLAY INVISIBLE (-850 3375);
FORCEPROP 1 LAST PATH I326
J 0
(-875 3675);
DISPLAY 0.978723 (-875 3675);
PAINT WHITE (-875 3675);
DISPLAY INVISIBLE (-875 3675);
FORCEPROP 2 LAST CDS_LIB pure_quanta
J 0
(-825 3525);
DISPLAY INVISIBLE (-825 3525);
FORCEPROP 1 LAST PACK_TYPE 0402LF
J 0
(-575 3375);
DISPLAY 0.510638 (-575 3375);
PAINT SKYBLUE (-575 3375);
DISPLAY INVISIBLE (-575 3375);
FORCEPROP 1 LAST LOCATION R489
J 0
(-1050 3525);
DISPLAY 0.702128 (-1050 3525);
PAINT YELLOW (-1050 3525);
FORCEPROP 1 LASTPIN (-925 3525) $PN 1
J 0
(-913 3537);
DISPLAY 0.808511 (-913 3537);
PAINT WHITE (-913 3537);
FORCEPROP 1 LASTPIN (-725 3525) $PN 2
J 0
(-763 3537);
DISPLAY 0.808511 (-763 3537);
PAINT WHITE (-763 3537);
FORCEPROP 0 LAST $SEC 1
J 0
(-1050 3575);
DISPLAY 0.680851 (-1050 3575);
PAINT MONO (-1050 3575);
DISPLAY INVISIBLE (-1050 3575);
FORCEPROP 0 LAST CDS_SEC 1
J 0
(-1050 3575);
DISPLAY 0.680851 (-1050 3575);
DISPLAY INVISIBLE (-1050 3575);
FORCEADD OFFPAGE..1
(-1950 3525);
FORCEPROP 2 LAST $XR2 36 
J 0
(-2351 3525);
DISPLAY 0.638298 (-2351 3525);
PAINT MONO (-2351 3525);
FORCEPROP 2 LAST $XR1 10 
J 0
(-2261 3525);
DISPLAY 0.638298 (-2261 3525);
PAINT MONO (-2261 3525);
FORCEPROP 2 LAST $XR0 28 
J 0
(-2171 3525);
DISPLAY 0.638298 (-2171 3525);
PAINT MONO (-2171 3525);
FORCEPROP 2 LAST PATH I327
J 0
(-1900 3600);
DISPLAY 0.680851 (-1900 3600);
DISPLAY INVISIBLE (-1900 3600);
FORCEPROP 1 LAST COMMENT_BODY TRUE
J 0
(-1825 3425);
DISPLAY 0.872340 (-1825 3425);
PAINT GREEN (-1825 3425);
DISPLAY INVISIBLE (-1825 3425);
FORCEPROP 1 LAST OFFPAGE TRUE
J 0
(-1625 3400);
DISPLAY 0.872340 (-1625 3400);
DISPLAY INVISIBLE (-1625 3400);
FORCEPROP 2 LAST CDS_LIB standard
J 0
(-1950 3525);
DISPLAY INVISIBLE (-1950 3525);
FORCEADD UNIVERSAL_POWER..1
(4325 -100);
FORCEPROP 3 LASTPIN (4325 -150) SIG_NAME P3V3_AUX\g
J 0
(4335 -140);
DISPLAY 0.659574 (4335 -140);
PAINT MONO (4335 -140);
DISPLAY INVISIBLE (4335 -140);
FORCEPROP 1 LAST HDL_POWER P3V3_AUX
J 1
(4325 -50);
DISPLAY 0.702128 (4325 -50);
PAINT GREEN (4325 -50);
FORCEPROP 1 LAST PATH I33
J 0
(4375 -75);
DISPLAY 0.872340 (4375 -75);
PAINT AQUA (4375 -75);
DISPLAY INVISIBLE (4375 -75);
FORCEPROP 2 LAST CDS_LIB logical_power
J 0
(4325 -100);
DISPLAY INVISIBLE (4325 -100);
FORCEADD Q_RES..1
(-825 3625);
FORCEPROP 1 LAST MATERIAL CHIP
J 0
(-600 3625);
DISPLAY 0.510638 (-600 3625);
PAINT SKYBLUE (-600 3625);
FORCEPROP 1 LAST VALUE 33.2
J 0
(-725 3625);
DISPLAY 0.510638 (-725 3625);
PAINT SKYBLUE (-725 3625);
FORCEPROP 1 LAST TOLERANCE 1%
J 0
(-700 3625);
DISPLAY 0.510638 (-700 3625);
PAINT SKYBLUE (-700 3625);
DISPLAY INVISIBLE (-700 3625);
FORCEPROP 1 LAST PART_NUMBER CS03322FB03
J 0
(-875 3725);
DISPLAY 0.510638 (-875 3725);
PAINT WHITE (-875 3725);
DISPLAY INVISIBLE (-875 3725);
FORCEPROP 1 LAST WATTAGE 1/16W
J 2
(-850 3475);
DISPLAY 0.510638 (-850 3475);
PAINT SKYBLUE (-850 3475);
DISPLAY INVISIBLE (-850 3475);
FORCEPROP 1 LAST PATH I330
J 0
(-875 3775);
DISPLAY 0.978723 (-875 3775);
PAINT WHITE (-875 3775);
DISPLAY INVISIBLE (-875 3775);
FORCEPROP 2 LAST CDS_LIB pure_quanta
J 0
(-825 3625);
DISPLAY INVISIBLE (-825 3625);
FORCEPROP 1 LAST PACK_TYPE 0402LF
J 0
(-575 3475);
DISPLAY 0.510638 (-575 3475);
PAINT SKYBLUE (-575 3475);
DISPLAY INVISIBLE (-575 3475);
FORCEPROP 1 LAST LOCATION R479
J 0
(-1050 3625);
DISPLAY 0.702128 (-1050 3625);
PAINT YELLOW (-1050 3625);
FORCEPROP 1 LASTPIN (-925 3625) $PN 1
J 0
(-913 3637);
DISPLAY 0.808511 (-913 3637);
PAINT WHITE (-913 3637);
FORCEPROP 1 LASTPIN (-725 3625) $PN 2
J 0
(-763 3637);
DISPLAY 0.808511 (-763 3637);
PAINT WHITE (-763 3637);
FORCEPROP 0 LAST $SEC 1
J 0
(-1050 3675);
DISPLAY 0.680851 (-1050 3675);
PAINT MONO (-1050 3675);
DISPLAY INVISIBLE (-1050 3675);
FORCEPROP 0 LAST CDS_SEC 1
J 0
(-1050 3675);
DISPLAY 0.680851 (-1050 3675);
DISPLAY INVISIBLE (-1050 3675);
FORCEADD OFFPAGE..5
(-1950 3625);
FORCEPROP 2 LAST $XR1 36 
J 0
(-2264 3625);
DISPLAY 0.638298 (-2264 3625);
PAINT MONO (-2264 3625);
FORCEPROP 2 LAST $XR0 42 
J 0
(-2174 3625);
DISPLAY 0.638298 (-2174 3625);
PAINT MONO (-2174 3625);
FORCEPROP 1 LAST OFFPAGE TRUE
J 0
(-1625 3500);
DISPLAY 0.872340 (-1625 3500);
DISPLAY INVISIBLE (-1625 3500);
FORCEPROP 1 LAST COMMENT_BODY TRUE
J 0
(-1850 3550);
DISPLAY 0.872340 (-1850 3550);
PAINT GREEN (-1850 3550);
DISPLAY INVISIBLE (-1850 3550);
FORCEPROP 2 LAST PATH I331
J 0
(-1900 3700);
DISPLAY 0.680851 (-1900 3700);
DISPLAY INVISIBLE (-1900 3700);
FORCEPROP 2 LAST CDS_LIB standard
J 0
(-1950 3625);
DISPLAY INVISIBLE (-1950 3625);
FORCEADD Q_RES..1
(4700 -350);
FORCEPROP 1 LAST VALUE 0
J 2
(4825 -350);
DISPLAY 0.510638 (4825 -350);
PAINT SKYBLUE (4825 -350);
FORCEPROP 1 LAST MATERIAL CHIP
J 0
(5000 -350);
DISPLAY 0.510638 (5000 -350);
PAINT SKYBLUE (5000 -350);
FORCEPROP 1 LAST PART_NUMBER CS00002JB13
J 0
(4850 -275);
DISPLAY 0.510638 (4850 -275);
PAINT WHITE (4850 -275);
FORCEPROP 1 LAST WATTAGE 1/16W
J 2
(4975 -350);
DISPLAY 0.510638 (4975 -350);
PAINT SKYBLUE (4975 -350);
FORCEPROP 1 LAST PACK_TYPE 0402LF
J 0
(5000 -250);
DISPLAY 0.510638 (5000 -250);
PAINT SKYBLUE (5000 -250);
DISPLAY INVISIBLE (5000 -250);
FORCEPROP 1 LAST TOLERANCE 5%
J 0
(5275 -250);
DISPLAY 0.510638 (5275 -250);
PAINT SKYBLUE (5275 -250);
DISPLAY INVISIBLE (5275 -250);
FORCEPROP 1 LAST PATH I34
J 0
(4650 -200);
DISPLAY 0.978723 (4650 -200);
PAINT WHITE (4650 -200);
DISPLAY INVISIBLE (4650 -200);
FORCEPROP 2 LAST CDS_LIB pure_quanta
J 0
(4700 -350);
DISPLAY INVISIBLE (4700 -350);
FORCEPROP 1 LAST LOCATION R213
J 0
(4450 -350);
DISPLAY 0.702128 (4450 -350);
PAINT YELLOW (4450 -350);
FORCEPROP 1 LASTPIN (4600 -350) $PN 1
J 0
(4612 -338);
DISPLAY 0.808511 (4612 -338);
PAINT WHITE (4612 -338);
FORCEPROP 1 LASTPIN (4800 -350) $PN 2
J 0
(4762 -338);
DISPLAY 0.808511 (4762 -338);
PAINT WHITE (4762 -338);
FORCEPROP 2 LAST $SEC 1
J 0
(4650 -125);
DISPLAY 0.680851 (4650 -125);
PAINT MONO (4650 -125);
DISPLAY INVISIBLE (4650 -125);
FORCEPROP 0 LAST CDS_SEC 1
J 0
(4650 -125);
DISPLAY 0.680851 (4650 -125);
PAINT MONO (4650 -125);
DISPLAY INVISIBLE (4650 -125);
FORCEADD OFFPAGE..5
R 2
(5125 3725);
FORCEPROP 2 LAST $XR1 34 
J 0
(5404 3725);
DISPLAY 0.638298 (5404 3725);
PAINT MONO (5404 3725);
FORCEPROP 2 LAST $XR0 42 
J 0
(5314 3725);
DISPLAY 0.638298 (5314 3725);
PAINT MONO (5314 3725);
FORCEPROP 2 LAST PATH I344
J 0
(5450 3775);
DISPLAY 0.680851 (5450 3775);
DISPLAY INVISIBLE (5450 3775);
FORCEPROP 1 LAST COMMENT_BODY TRUE
J 2
(5025 3650);
DISPLAY 0.872340 (5025 3650);
PAINT GREEN (5025 3650);
DISPLAY INVISIBLE (5025 3650);
FORCEPROP 1 LAST OFFPAGE TRUE
J 2
(4800 3600);
DISPLAY 0.872340 (4800 3600);
DISPLAY INVISIBLE (4800 3600);
FORCEPROP 2 LAST CDS_LIB standard
J 2
(5125 3725);
DISPLAY INVISIBLE (5125 3725);
FORCEADD Q_RES..1
R 2
(4025 3725);
FORCEPROP 1 LAST VALUE 33.2
J 2
(3925 3725);
DISPLAY 0.510638 (3925 3725);
PAINT SKYBLUE (3925 3725);
FORCEPROP 1 LAST MATERIAL CHIP
J 2
(3800 3725);
DISPLAY 0.510638 (3800 3725);
PAINT SKYBLUE (3800 3725);
FORCEPROP 1 LAST TOLERANCE 1%
J 2
(3900 3725);
DISPLAY 0.510638 (3900 3725);
PAINT SKYBLUE (3900 3725);
DISPLAY INVISIBLE (3900 3725);
FORCEPROP 1 LAST PART_NUMBER CS03322FB03
J 2
(4075 3825);
DISPLAY 0.510638 (4075 3825);
PAINT WHITE (4075 3825);
DISPLAY INVISIBLE (4075 3825);
FORCEPROP 1 LAST PACK_TYPE 0402LF
J 2
(3775 3575);
DISPLAY 0.510638 (3775 3575);
PAINT SKYBLUE (3775 3575);
DISPLAY INVISIBLE (3775 3575);
FORCEPROP 1 LAST WATTAGE 1/16W
J 0
(4050 3575);
DISPLAY 0.510638 (4050 3575);
PAINT SKYBLUE (4050 3575);
DISPLAY INVISIBLE (4050 3575);
FORCEPROP 1 LAST PATH I345
J 2
(4075 3875);
DISPLAY 0.978723 (4075 3875);
PAINT WHITE (4075 3875);
DISPLAY INVISIBLE (4075 3875);
FORCEPROP 2 LAST CDS_LIB pure_quanta
J 2
(4025 3725);
DISPLAY INVISIBLE (4025 3725);
FORCEPROP 1 LAST LOCATION R644
J 2
(4250 3725);
DISPLAY 0.702128 (4250 3725);
PAINT YELLOW (4250 3725);
FORCEPROP 1 LASTPIN (4125 3725) $PN 1
J 2
(4113 3737);
DISPLAY 0.808511 (4113 3737);
PAINT WHITE (4113 3737);
FORCEPROP 1 LASTPIN (3925 3725) $PN 2
J 2
(3963 3737);
DISPLAY 0.808511 (3963 3737);
PAINT WHITE (3963 3737);
FORCEPROP 2 LAST $SEC 1
J 2
(4075 3925);
DISPLAY 0.680851 (4075 3925);
PAINT MONO (4075 3925);
DISPLAY INVISIBLE (4075 3925);
FORCEPROP 0 LAST CDS_SEC 1
J 2
(4075 3925);
DISPLAY 0.680851 (4075 3925);
PAINT MONO (4075 3925);
DISPLAY INVISIBLE (4075 3925);
FORCEADD Q_RES..2
(-2650 4275);
FORCEPROP 1 LAST VALUE 4.7K
J 0
(-2600 4300);
DISPLAY 0.510638 (-2600 4300);
PAINT SKYBLUE (-2600 4300);
FORCEPROP 1 LAST TOLERANCE 1%
J 0
(-2600 4250);
DISPLAY 0.510638 (-2600 4250);
PAINT SKYBLUE (-2600 4250);
FORCEPROP 1 LAST MATERIAL EMPTY
J 0
(-2600 4200);
DISPLAY 0.510638 (-2600 4200);
PAINT RED (-2600 4200);
FORCEPROP 1 LAST PART_NUMBER CS24702FB06
J 0
(-2610 4150);
DISPLAY 0.510638 (-2610 4150);
PAINT WHITE (-2610 4150);
DISPLAY INVISIBLE (-2610 4150);
FORCEPROP 1 LAST PACK_TYPE 0402LF
J 0
(-2610 4100);
DISPLAY 0.510638 (-2610 4100);
PAINT SKYBLUE (-2610 4100);
DISPLAY INVISIBLE (-2610 4100);
FORCEPROP 1 LAST WATTAGE 1/16W
J 0
(-2610 4250);
DISPLAY 0.510638 (-2610 4250);
PAINT SKYBLUE (-2610 4250);
DISPLAY INVISIBLE (-2610 4250);
FORCEPROP 1 LAST PATH I346
J 0
(-2600 4450);
DISPLAY 0.978723 (-2600 4450);
PAINT WHITE (-2600 4450);
DISPLAY INVISIBLE (-2600 4450);
FORCEPROP 2 LAST CDS_LIB pure_quanta
J 0
(-2650 4275);
DISPLAY INVISIBLE (-2650 4275);
FORCEPROP 1 LAST LOCATION R491
J 0
(-2600 4350);
DISPLAY 0.702128 (-2600 4350);
PAINT YELLOW (-2600 4350);
FORCEPROP 1 LASTPIN (-2650 4375) $PN 1
J 0
(-2645 4337);
DISPLAY 0.808511 (-2645 4337);
PAINT WHITE (-2645 4337);
FORCEPROP 1 LASTPIN (-2650 4175) $PN 2
J 0
(-2645 4185);
DISPLAY 0.808511 (-2645 4185);
PAINT WHITE (-2645 4185);
FORCEPROP 0 LAST $SEC 1
J 0
(-2600 4450);
DISPLAY 0.680851 (-2600 4450);
PAINT MONO (-2600 4450);
DISPLAY INVISIBLE (-2600 4450);
FORCEPROP 0 LAST CDS_SEC 1
J 0
(-2600 4450);
DISPLAY 0.680851 (-2600 4450);
DISPLAY INVISIBLE (-2600 4450);
FORCEADD OFFPAGE..2
(-2000 4125);
FORCEPROP 2 LAST $XR0 22 
J 0
(-1811 4125);
DISPLAY 0.638298 (-1811 4125);
PAINT MONO (-1811 4125);
FORCEPROP 2 LAST $XR1 15 
J 0
(-1721 4125);
DISPLAY 0.638298 (-1721 4125);
PAINT MONO (-1721 4125);
FORCEPROP 2 LAST PATH I347
J 0
(-1625 4175);
DISPLAY 0.680851 (-1625 4175);
DISPLAY INVISIBLE (-1625 4175);
FORCEPROP 1 LAST COMMENT_BODY TRUE
J 0
(-2045 4030);
DISPLAY 0.872340 (-2045 4030);
PAINT PEACH (-2045 4030);
DISPLAY INVISIBLE (-2045 4030);
FORCEPROP 1 LAST OFFPAGE TRUE
J 0
(-1675 4000);
DISPLAY 0.872340 (-1675 4000);
PAINT GREEN (-1675 4000);
DISPLAY INVISIBLE (-1675 4000);
FORCEPROP 2 LAST CDS_LIB standard
J 2
(-2000 4125);
DISPLAY INVISIBLE (-2000 4125);
FORCEADD UNIVERSAL_GND..1
(5525 -800);
FORCEPROP 3 LASTPIN (5525 -750) SIG_NAME GND\g
J 0
(5535 -740);
DISPLAY 0.659574 (5535 -740);
PAINT MONO (5535 -740);
DISPLAY INVISIBLE (5535 -740);
FORCEPROP 1 LAST PATH I35
J 0
(5600 -800);
DISPLAY 0.872340 (5600 -800);
PAINT AQUA (5600 -800);
DISPLAY INVISIBLE (5600 -800);
FORCEPROP 1 LAST HDL_POWER GND
J 1
(5550 -875);
DISPLAY 0.702128 (5550 -875);
PAINT GREEN (5550 -875);
DISPLAY INVISIBLE (5550 -875);
FORCEPROP 2 LAST CDS_LIB logical_power
J 0
(5525 -800);
DISPLAY INVISIBLE (5525 -800);
FORCEADD AST2600A3GP..4
(1350 2900);
FORCEPROP 1 LAST MATERIAL IC
J 0
(602 4381);
DISPLAY 0.723404 (602 4381);
PAINT GREEN (602 4381);
FORCEPROP 1 LAST PART_NUMBER AJ026000T06
J 0
(602 4468);
DISPLAY 0.723404 (602 4468);
PAINT GREEN (602 4468);
FORCEPROP 2 LAST PART_TYPE SMLF
J 0
(625 4675);
DISPLAY 0.680851 (625 4675);
FORCEPROP 2 LAST VALUE AST2600A3-GP
J 0
(625 4625);
DISPLAY 0.680851 (625 4625);
FORCEPROP 2 LAST CDS_LIB pure_quanta
J 0
(1350 2900);
DISPLAY INVISIBLE (1350 2900);
FORCEPROP 1 LAST PATH I350
J 0
(1350 2900);
DISPLAY 0.723404 (1350 2900);
PAINT GREEN (1350 2900);
DISPLAY INVISIBLE (1350 2900);
FORCEPROP 1 LAST CDS_LMAN_SYM_OUTLINE -750,1475,750,-1475
J 0
(1350 2900);
DISPLAY 0.468085 (1350 2900);
PAINT GREEN (1350 2900);
DISPLAY INVISIBLE (1350 2900);
FORCEPROP 1 LAST NEEDS_NO_SIZE TRUE
J 0
(1350 2900);
DISPLAY 0.723404 (1350 2900);
PAINT GREEN (1350 2900);
DISPLAY INVISIBLE (1350 2900);
FORCEPROP 1 LAST LOCATION U5
J 0
(602 4575);
DISPLAY 0.723404 (602 4575);
PAINT GREEN (602 4575);
FORCEPROP 0 LASTPIN (450 3025) $PN AD20
J 2
(440 3035);
DISPLAY 0.680851 (440 3035);
PAINT MONO (440 3035);
FORCEPROP 0 LASTPIN (450 2975) $PN AC18
J 2
(440 2985);
DISPLAY 0.680851 (440 2985);
PAINT MONO (440 2985);
FORCEPROP 0 LASTPIN (450 2925) $PN AE19
J 2
(440 2935);
DISPLAY 0.680851 (440 2935);
PAINT MONO (440 2935);
FORCEPROP 0 LASTPIN (450 2875) $PN AD19
J 2
(440 2885);
DISPLAY 0.680851 (440 2885);
PAINT MONO (440 2885);
FORCEPROP 0 LASTPIN (450 2825) $PN AC19
J 2
(440 2835);
DISPLAY 0.680851 (440 2835);
PAINT MONO (440 2835);
FORCEPROP 0 LASTPIN (450 2775) $PN AB19
J 2
(440 2785);
DISPLAY 0.680851 (440 2785);
PAINT MONO (440 2785);
FORCEPROP 0 LASTPIN (450 2725) $PN AB18
J 2
(440 2735);
DISPLAY 0.680851 (440 2735);
PAINT MONO (440 2735);
FORCEPROP 0 LASTPIN (450 2675) $PN AE18
J 2
(440 2685);
DISPLAY 0.680851 (440 2685);
PAINT MONO (440 2685);
FORCEPROP 0 LASTPIN (450 2625) $PN AB16
J 2
(440 2635);
DISPLAY 0.680851 (440 2635);
PAINT MONO (440 2635);
FORCEPROP 0 LASTPIN (450 2575) $PN AA17
J 2
(440 2585);
DISPLAY 0.680851 (440 2585);
PAINT MONO (440 2585);
FORCEPROP 0 LASTPIN (450 2525) $PN AB17
J 2
(440 2535);
DISPLAY 0.680851 (440 2535);
PAINT MONO (440 2535);
FORCEPROP 0 LASTPIN (450 2475) $PN AE16
J 2
(440 2485);
DISPLAY 0.680851 (440 2485);
PAINT MONO (440 2485);
FORCEPROP 0 LASTPIN (450 2425) $PN AC16
J 2
(440 2435);
DISPLAY 0.680851 (440 2435);
PAINT MONO (440 2435);
FORCEPROP 0 LASTPIN (450 2375) $PN AA16
J 2
(440 2385);
DISPLAY 0.680851 (440 2385);
PAINT MONO (440 2385);
FORCEPROP 0 LASTPIN (450 2325) $PN AD16
J 2
(440 2335);
DISPLAY 0.680851 (440 2335);
PAINT MONO (440 2335);
FORCEPROP 0 LASTPIN (450 2275) $PN AC17
J 2
(440 2285);
DISPLAY 0.680851 (440 2285);
PAINT MONO (440 2285);
FORCEPROP 0 LASTPIN (2250 1525) $PN AB21
J 0
(2260 1535);
DISPLAY 0.680851 (2260 1535);
PAINT MONO (2260 1535);
FORCEPROP 0 LASTPIN (450 4325) $PN D10
J 2
(440 4335);
DISPLAY 0.680851 (440 4335);
PAINT MONO (440 4335);
FORCEPROP 0 LASTPIN (2250 4325) $PN AD21
J 0
(2260 4335);
DISPLAY 0.680851 (2260 4335);
PAINT MONO (2260 4335);
FORCEPROP 0 LASTPIN (2250 4275) $PN AE21
J 0
(2260 4285);
DISPLAY 0.680851 (2260 4285);
PAINT MONO (2260 4285);
FORCEPROP 0 LASTPIN (2250 4225) $PN AF21
J 0
(2260 4235);
DISPLAY 0.680851 (2260 4235);
PAINT MONO (2260 4235);
FORCEPROP 0 LASTPIN (2250 4025) $PN B8
J 0
(2260 4035);
DISPLAY 0.680851 (2260 4035);
PAINT MONO (2260 4035);
FORCEPROP 0 LASTPIN (2250 3975) $PN A8
J 0
(2260 3985);
DISPLAY 0.680851 (2260 3985);
PAINT MONO (2260 3985);
FORCEPROP 0 LASTPIN (450 3975) $PN C10
J 2
(440 3985);
DISPLAY 0.680851 (440 3985);
PAINT MONO (440 3985);
FORCEPROP 0 LASTPIN (450 4125) $PN B10
J 2
(440 4135);
DISPLAY 0.680851 (440 4135);
PAINT MONO (440 4135);
FORCEPROP 0 LASTPIN (2250 2125) $PN D17
J 0
(2260 2135);
DISPLAY 0.680851 (2260 2135);
PAINT MONO (2260 2135);
FORCEPROP 0 LASTPIN (2250 1975) $PN A16
J 0
(2260 1985);
DISPLAY 0.680851 (2260 1985);
PAINT MONO (2260 1985);
FORCEPROP 0 LASTPIN (2250 2075) $PN E17
J 0
(2260 2085);
DISPLAY 0.680851 (2260 2085);
PAINT MONO (2260 2085);
FORCEPROP 0 LASTPIN (2250 2025) $PN D16
J 0
(2260 2035);
DISPLAY 0.680851 (2260 2035);
PAINT MONO (2260 2035);
FORCEPROP 0 LASTPIN (450 1975) $PN C16
J 2
(440 1985);
DISPLAY 0.680851 (440 1985);
PAINT MONO (440 1985);
FORCEPROP 0 LASTPIN (2250 4125) $PN B14
J 0
(2260 4135);
DISPLAY 0.680851 (2260 4135);
PAINT MONO (2260 4135);
FORCEPROP 0 LASTPIN (2250 4075) $PN C14
J 0
(2260 4085);
DISPLAY 0.680851 (2260 4085);
PAINT MONO (2260 4085);
FORCEPROP 0 LASTPIN (2250 3875) $PN AD26
J 0
(2260 3885);
DISPLAY 0.680851 (2260 3885);
PAINT MONO (2260 3885);
FORCEPROP 0 LASTPIN (2250 3825) $PN AD22
J 0
(2260 3835);
DISPLAY 0.680851 (2260 3835);
PAINT MONO (2260 3835);
FORCEPROP 0 LASTPIN (2250 3775) $PN AD23
J 0
(2260 3785);
DISPLAY 0.680851 (2260 3785);
PAINT MONO (2260 3785);
FORCEPROP 0 LASTPIN (2250 3725) $PN AD24
J 0
(2260 3735);
DISPLAY 0.680851 (2260 3735);
PAINT MONO (2260 3735);
FORCEPROP 0 LASTPIN (2250 3675) $PN AD25
J 0
(2260 3685);
DISPLAY 0.680851 (2260 3685);
PAINT MONO (2260 3685);
FORCEPROP 0 LASTPIN (2250 3625) $PN AC22
J 0
(2260 3635);
DISPLAY 0.680851 (2260 3635);
PAINT MONO (2260 3635);
FORCEPROP 0 LASTPIN (2250 3575) $PN AC24
J 0
(2260 3585);
DISPLAY 0.680851 (2260 3585);
PAINT MONO (2260 3585);
FORCEPROP 0 LASTPIN (2250 3525) $PN AC23
J 0
(2260 3535);
DISPLAY 0.680851 (2260 3535);
PAINT MONO (2260 3535);
FORCEPROP 0 LASTPIN (2250 3475) $PN AB22
J 0
(2260 3485);
DISPLAY 0.680851 (2260 3485);
PAINT MONO (2260 3485);
FORCEPROP 0 LASTPIN (2250 3425) $PN W24
J 0
(2260 3435);
DISPLAY 0.680851 (2260 3435);
PAINT MONO (2260 3435);
FORCEPROP 0 LASTPIN (2250 3375) $PN AA23
J 0
(2260 3385);
DISPLAY 0.680851 (2260 3385);
PAINT MONO (2260 3385);
FORCEPROP 0 LASTPIN (2250 3325) $PN AA24
J 0
(2260 3335);
DISPLAY 0.680851 (2260 3335);
PAINT MONO (2260 3335);
FORCEPROP 0 LASTPIN (2250 3275) $PN W23
J 0
(2260 3285);
DISPLAY 0.680851 (2260 3285);
PAINT MONO (2260 3285);
FORCEPROP 0 LASTPIN (2250 3225) $PN AB23
J 0
(2260 3235);
DISPLAY 0.680851 (2260 3235);
PAINT MONO (2260 3235);
FORCEPROP 0 LASTPIN (2250 3175) $PN AB24
J 0
(2260 3185);
DISPLAY 0.680851 (2260 3185);
PAINT MONO (2260 3185);
FORCEPROP 0 LASTPIN (2250 3125) $PN Y23
J 0
(2260 3135);
DISPLAY 0.680851 (2260 3135);
PAINT MONO (2260 3135);
FORCEPROP 0 LASTPIN (450 3875) $PN AA25
J 2
(440 3885);
DISPLAY 0.680851 (440 3885);
PAINT MONO (440 3885);
FORCEPROP 0 LASTPIN (450 3825) $PN AB25
J 2
(440 3835);
DISPLAY 0.680851 (440 3835);
PAINT MONO (440 3835);
FORCEPROP 0 LASTPIN (450 3775) $PN Y24
J 2
(440 3785);
DISPLAY 0.680851 (440 3785);
PAINT MONO (440 3785);
FORCEPROP 0 LASTPIN (450 3725) $PN AB26
J 2
(440 3735);
DISPLAY 0.680851 (440 3735);
PAINT MONO (440 3735);
FORCEPROP 0 LASTPIN (450 3675) $PN Y26
J 2
(440 3685);
DISPLAY 0.680851 (440 3685);
PAINT MONO (440 3685);
FORCEPROP 0 LASTPIN (450 3625) $PN AC26
J 2
(440 3635);
DISPLAY 0.680851 (440 3635);
PAINT MONO (440 3635);
FORCEPROP 0 LASTPIN (450 3575) $PN Y25
J 2
(440 3585);
DISPLAY 0.680851 (440 3585);
PAINT MONO (440 3585);
FORCEPROP 0 LASTPIN (450 3525) $PN AA26
J 2
(440 3535);
DISPLAY 0.680851 (440 3535);
PAINT MONO (440 3535);
FORCEPROP 0 LASTPIN (450 3475) $PN V25
J 2
(440 3485);
DISPLAY 0.680851 (440 3485);
PAINT MONO (440 3485);
FORCEPROP 0 LASTPIN (450 3425) $PN U24
J 2
(440 3435);
DISPLAY 0.680851 (440 3435);
PAINT MONO (440 3435);
FORCEPROP 0 LASTPIN (450 3375) $PN V24
J 2
(440 3385);
DISPLAY 0.680851 (440 3385);
PAINT MONO (440 3385);
FORCEPROP 0 LASTPIN (450 3325) $PN V26
J 2
(440 3335);
DISPLAY 0.680851 (440 3335);
PAINT MONO (440 3335);
FORCEPROP 0 LASTPIN (450 3275) $PN U25
J 2
(440 3285);
DISPLAY 0.680851 (440 3285);
PAINT MONO (440 3285);
FORCEPROP 0 LASTPIN (450 3225) $PN T23
J 2
(440 3235);
DISPLAY 0.680851 (440 3235);
PAINT MONO (440 3235);
FORCEPROP 0 LASTPIN (450 3175) $PN W26
J 2
(440 3185);
DISPLAY 0.680851 (440 3185);
PAINT MONO (440 3185);
FORCEPROP 0 LASTPIN (450 3125) $PN U26
J 2
(440 3135);
DISPLAY 0.680851 (440 3135);
PAINT MONO (440 3135);
FORCEPROP 0 LASTPIN (450 1825) $PN F11
J 2
(440 1835);
DISPLAY 0.680851 (440 1835);
PAINT MONO (440 1835);
FORCEPROP 0 LASTPIN (2250 2325) $PN AF16
J 0
(2260 2335);
DISPLAY 0.680851 (2260 2335);
PAINT MONO (2260 2335);
FORCEPROP 0 LASTPIN (2250 2375) $PN AA18
J 0
(2260 2385);
DISPLAY 0.680851 (2260 2385);
PAINT MONO (2260 2385);
FORCEPROP 0 LASTPIN (450 4025) $PN B7
J 2
(440 4035);
DISPLAY 0.680851 (440 4035);
PAINT MONO (440 4035);
FORCEPROP 0 LASTPIN (450 4225) $PN E10
J 2
(440 4235);
DISPLAY 0.680851 (440 4235);
PAINT MONO (440 4235);
FORCEPROP 0 LASTPIN (450 4175) $PN D7
J 2
(440 4185);
DISPLAY 0.680851 (440 4185);
PAINT MONO (440 4185);
FORCEPROP 0 LASTPIN (450 1775) $PN B9
J 2
(440 1785);
DISPLAY 0.680851 (440 1785);
PAINT MONO (440 1785);
FORCEPROP 0 LASTPIN (450 1675) $PN D9
J 2
(440 1685);
DISPLAY 0.680851 (440 1685);
PAINT MONO (440 1685);
FORCEPROP 0 LASTPIN (2250 1675) $PN C9
J 0
(2260 1685);
DISPLAY 0.680851 (2260 1685);
PAINT MONO (2260 1685);
FORCEPROP 0 LASTPIN (450 1725) $PN A9
J 2
(440 1735);
DISPLAY 0.680851 (440 1735);
PAINT MONO (440 1735);
FORCEPROP 0 LASTPIN (2250 2775) $PN B4
J 0
(2260 2785);
DISPLAY 0.680851 (2260 2785);
PAINT MONO (2260 2785);
FORCEPROP 0 LASTPIN (2250 2825) $PN A4
J 0
(2260 2835);
DISPLAY 0.680851 (2260 2835);
PAINT MONO (2260 2835);
FORCEPROP 0 LASTPIN (2250 2925) $PN K10
J 0
(2260 2935);
DISPLAY 0.680851 (2260 2935);
PAINT MONO (2260 2935);
FORCEPROP 0 LASTPIN (2250 2975) $PN J10
J 0
(2260 2985);
DISPLAY 0.680851 (2260 2985);
PAINT MONO (2260 2985);
FORCEPROP 0 LASTPIN (2250 2625) $PN B6
J 0
(2260 2635);
DISPLAY 0.680851 (2260 2635);
PAINT MONO (2260 2635);
FORCEPROP 0 LASTPIN (2250 2675) $PN A6
J 0
(2260 2685);
DISPLAY 0.680851 (2260 2685);
PAINT MONO (2260 2685);
FORCEPROP 0 LAST $SEC 4
J 0
(625 4725);
DISPLAY 0.680851 (625 4725);
PAINT MONO (625 4725);
DISPLAY INVISIBLE (625 4725);
FORCEPROP 0 LAST CDS_SEC 4
J 0
(625 4725);
DISPLAY 0.680851 (625 4725);
DISPLAY INVISIBLE (625 4725);
FORCEADD Q_RES..1
R 2
(-300 1975);
FORCEPROP 1 LAST TOLERANCE 5%
J 2
(-150 1950);
DISPLAY 0.510638 (-150 1950);
PAINT SKYBLUE (-150 1950);
FORCEPROP 1 LAST MATERIAL CHIP
J 2
(-25 1950);
DISPLAY 0.510638 (-25 1950);
PAINT SKYBLUE (-25 1950);
FORCEPROP 1 LAST WATTAGE 1/16W
J 0
(0 1950);
DISPLAY 0.510638 (0 1950);
PAINT SKYBLUE (0 1950);
FORCEPROP 1 LAST VALUE 0
J 0
(-250 1950);
DISPLAY 0.510638 (-250 1950);
PAINT SKYBLUE (-250 1950);
FORCEPROP 1 LAST PACK_TYPE 0402LF
J 2
(300 1950);
DISPLAY 0.510638 (300 1950);
PAINT SKYBLUE (300 1950);
FORCEPROP 1 LAST PART_NUMBER CS00002JB13
J 2
(-50 2000);
DISPLAY 0.510638 (-50 2000);
PAINT WHITE (-50 2000);
DISPLAY INVISIBLE (-50 2000);
FORCEPROP 1 LAST PATH I351
J 2
(-250 2125);
DISPLAY 0.978723 (-250 2125);
PAINT WHITE (-250 2125);
DISPLAY INVISIBLE (-250 2125);
FORCEPROP 2 LAST CDS_LIB pure_quanta
J 0
(-300 1975);
DISPLAY INVISIBLE (-300 1975);
FORCEPROP 1 LAST $LOCATION R398
J 2
(-400 1975);
DISPLAY 0.702128 (-400 1975);
PAINT YELLOW (-400 1975);
FORCEPROP 1 LASTPIN (-200 1975) $PN 1
J 2
(-212 1987);
DISPLAY 0.787234 (-212 1987);
PAINT MONO (-212 1987);
FORCEPROP 1 LASTPIN (-400 1975) $PN 2
J 2
(-362 1987);
DISPLAY 0.787234 (-362 1987);
PAINT MONO (-362 1987);
FORCEPROP 0 LAST CDS_LOCATION R398
J 0
(-350 2025);
DISPLAY 0.680851 (-350 2025);
DISPLAY INVISIBLE (-350 2025);
FORCEPROP 0 LAST $SEC 1
J 0
(-350 2025);
DISPLAY 0.680851 (-350 2025);
PAINT MONO (-350 2025);
DISPLAY INVISIBLE (-350 2025);
FORCEPROP 0 LAST CDS_SEC 1
J 0
(-350 2025);
DISPLAY 0.680851 (-350 2025);
DISPLAY INVISIBLE (-350 2025);
FORCEADD OFFPAGE..1
(-1125 1975);
FORCEPROP 2 LAST $XR0 32 
J 0
(-1346 1975);
DISPLAY 0.638298 (-1346 1975);
PAINT MONO (-1346 1975);
FORCEPROP 2 LAST PATH I352
J 0
(-1325 2025);
DISPLAY 0.680851 (-1325 2025);
DISPLAY INVISIBLE (-1325 2025);
FORCEPROP 1 LAST COMMENT_BODY TRUE
J 0
(-1000 1875);
DISPLAY 0.872340 (-1000 1875);
PAINT PEACH (-1000 1875);
DISPLAY INVISIBLE (-1000 1875);
FORCEPROP 1 LAST OFFPAGE TRUE
J 0
(-800 1850);
DISPLAY 0.872340 (-800 1850);
PAINT GREEN (-800 1850);
DISPLAY INVISIBLE (-800 1850);
FORCEPROP 2 LAST CDS_LIB standard
J 0
(-1125 1975);
DISPLAY INVISIBLE (-1125 1975);
FORCEADD Q_RES..1
(3900 2975);
FORCEPROP 1 LAST VALUE 49.9
J 2
(3850 2975);
DISPLAY 0.510638 (3850 2975);
PAINT SKYBLUE (3850 2975);
FORCEPROP 1 LAST MATERIAL EMPTY
J 0
(4000 2950);
DISPLAY 0.510638 (4000 2950);
PAINT RED (4000 2950);
FORCEPROP 1 LAST WATTAGE 1/16W
J 2
(3875 2825);
DISPLAY 0.510638 (3875 2825);
PAINT SKYBLUE (3875 2825);
DISPLAY INVISIBLE (3875 2825);
FORCEPROP 1 LAST PART_NUMBER CS04992FB07
J 0
(3375 2875);
DISPLAY 0.510638 (3375 2875);
PAINT WHITE (3375 2875);
DISPLAY INVISIBLE (3375 2875);
FORCEPROP 1 LAST TOLERANCE 1%
J 0
(3900 2875);
DISPLAY 0.510638 (3900 2875);
PAINT SKYBLUE (3900 2875);
DISPLAY INVISIBLE (3900 2875);
FORCEPROP 1 LAST PATH I353
J 0
(3850 3125);
DISPLAY 0.978723 (3850 3125);
PAINT WHITE (3850 3125);
DISPLAY INVISIBLE (3850 3125);
FORCEPROP 2 LAST CDS_LIB pure_quanta
J 0
(3900 2975);
DISPLAY INVISIBLE (3900 2975);
FORCEPROP 1 LAST PACK_TYPE 0402LF
J 0
(3975 2875);
DISPLAY 0.510638 (3975 2875);
PAINT SKYBLUE (3975 2875);
DISPLAY INVISIBLE (3975 2875);
FORCEPROP 1 LAST $LOCATION R441
J 0
(4000 2975);
DISPLAY 0.702128 (4000 2975);
PAINT YELLOW (4000 2975);
FORCEPROP 1 LASTPIN (3800 2975) $PN 1
J 0
(3812 2987);
DISPLAY 0.787234 (3812 2987);
PAINT MONO (3812 2987);
FORCEPROP 1 LASTPIN (4000 2975) $PN 2
J 0
(3962 2987);
DISPLAY 0.787234 (3962 2987);
PAINT MONO (3962 2987);
FORCEPROP 0 LAST CDS_LOCATION R441
J 0
(3950 3025);
DISPLAY 0.680851 (3950 3025);
DISPLAY INVISIBLE (3950 3025);
FORCEPROP 0 LAST $SEC 1
J 0
(4000 3025);
DISPLAY 0.680851 (4000 3025);
PAINT MONO (4000 3025);
DISPLAY INVISIBLE (4000 3025);
FORCEPROP 0 LAST CDS_SEC 1
J 0
(4000 3025);
DISPLAY 0.680851 (4000 3025);
DISPLAY INVISIBLE (4000 3025);
FORCEADD Q_RES..1
(3900 3050);
FORCEPROP 1 LAST VALUE 49.9
J 2
(3850 3050);
DISPLAY 0.510638 (3850 3050);
PAINT SKYBLUE (3850 3050);
FORCEPROP 1 LAST MATERIAL EMPTY
J 0
(4000 3025);
DISPLAY 0.510638 (4000 3025);
PAINT RED (4000 3025);
FORCEPROP 1 LAST TOLERANCE 1%
J 0
(3900 2950);
DISPLAY 0.510638 (3900 2950);
PAINT SKYBLUE (3900 2950);
DISPLAY INVISIBLE (3900 2950);
FORCEPROP 1 LAST PART_NUMBER CS04992FB07
J 0
(3375 2950);
DISPLAY 0.510638 (3375 2950);
PAINT WHITE (3375 2950);
DISPLAY INVISIBLE (3375 2950);
FORCEPROP 1 LAST WATTAGE 1/16W
J 2
(3875 2900);
DISPLAY 0.510638 (3875 2900);
PAINT SKYBLUE (3875 2900);
DISPLAY INVISIBLE (3875 2900);
FORCEPROP 1 LAST PATH I354
J 0
(3850 3200);
DISPLAY 0.978723 (3850 3200);
PAINT WHITE (3850 3200);
DISPLAY INVISIBLE (3850 3200);
FORCEPROP 2 LAST CDS_LIB pure_quanta
J 0
(3900 3050);
DISPLAY INVISIBLE (3900 3050);
FORCEPROP 1 LAST PACK_TYPE 0402LF
J 0
(3975 2950);
DISPLAY 0.510638 (3975 2950);
PAINT SKYBLUE (3975 2950);
DISPLAY INVISIBLE (3975 2950);
FORCEPROP 1 LAST $LOCATION R440
J 0
(4000 3050);
DISPLAY 0.638298 (4000 3050);
FORCEPROP 1 LASTPIN (3800 3050) $PN 1
J 0
(3812 3062);
DISPLAY 0.787234 (3812 3062);
PAINT MONO (3812 3062);
FORCEPROP 1 LASTPIN (4000 3050) $PN 2
J 0
(3962 3062);
DISPLAY 0.787234 (3962 3062);
PAINT MONO (3962 3062);
FORCEPROP 0 LAST CDS_LOCATION R440
J 0
(3975 3100);
DISPLAY 0.680851 (3975 3100);
DISPLAY INVISIBLE (3975 3100);
FORCEPROP 0 LAST $SEC 1
J 0
(4000 3100);
DISPLAY 0.680851 (4000 3100);
PAINT MONO (4000 3100);
DISPLAY INVISIBLE (4000 3100);
FORCEPROP 0 LAST CDS_SEC 1
J 0
(4000 3100);
DISPLAY 0.680851 (4000 3100);
DISPLAY INVISIBLE (4000 3100);
FORCEADD UNIVERSAL_GND..1
(4200 2900);
FORCEPROP 3 LASTPIN (4200 2950) SIG_NAME GND\g
J 0
(4210 2960);
DISPLAY 0.659574 (4210 2960);
PAINT MONO (4210 2960);
DISPLAY INVISIBLE (4210 2960);
FORCEPROP 1 LAST HDL_POWER GND
J 1
(4225 2825);
DISPLAY 0.702128 (4225 2825);
PAINT GREEN (4225 2825);
DISPLAY INVISIBLE (4225 2825);
FORCEPROP 1 LAST PATH I355
J 0
(4275 2900);
DISPLAY 0.872340 (4275 2900);
PAINT AQUA (4275 2900);
DISPLAY INVISIBLE (4275 2900);
FORCEPROP 2 LAST CDS_LIB logical_power
J 0
(4200 2900);
DISPLAY INVISIBLE (4200 2900);
FORCEADD OFFPAGE..2
R 2
(-1500 4025);
FORCEPROP 2 LAST $XR0 25 
J 0
(-1724 4025);
DISPLAY 0.638298 (-1724 4025);
PAINT MONO (-1724 4025);
FORCEPROP 2 LAST CDS_LIB standard
J 0
(-1500 4025);
DISPLAY INVISIBLE (-1500 4025);
FORCEPROP 2 LAST PATH I357
J 0
(-1450 4100);
DISPLAY 0.680851 (-1450 4100);
DISPLAY INVISIBLE (-1450 4100);
FORCEPROP 1 LAST COMMENT_BODY TRUE
J 2
(-1455 3930);
DISPLAY 0.872340 (-1455 3930);
PAINT PEACH (-1455 3930);
DISPLAY INVISIBLE (-1455 3930);
FORCEPROP 1 LAST OFFPAGE TRUE
J 2
(-1825 3900);
DISPLAY 0.872340 (-1825 3900);
PAINT GREEN (-1825 3900);
DISPLAY INVISIBLE (-1825 3900);
FORCEADD Q_CAP..1
(5450 -525);
FORCEPROP 1 LAST PACK_TYPE C0402
J 0
(5475 -675);
DISPLAY 0.510638 (5475 -675);
PAINT SKYBLUE (5475 -675);
FORCEPROP 1 LAST MATERIAL X6S
J 0
(5500 -625);
DISPLAY 0.510638 (5500 -625);
PAINT SKYBLUE (5500 -625);
FORCEPROP 1 LAST TOLERANCE 10%
J 0
(5500 -575);
DISPLAY 0.510638 (5500 -575);
PAINT SKYBLUE (5500 -575);
FORCEPROP 1 LAST VOLTAGE 25V
J 0
(5500 -525);
DISPLAY 0.510638 (5500 -525);
PAINT SKYBLUE (5500 -525);
FORCEPROP 1 LAST VALUE 1UF
J 0
(5500 -475);
DISPLAY 0.510638 (5500 -475);
PAINT SKYBLUE (5500 -475);
FORCEPROP 1 LAST PATH I36
J 0
(5500 -375);
DISPLAY 0.978723 (5500 -375);
PAINT WHITE (5500 -375);
DISPLAY INVISIBLE (5500 -375);
FORCEPROP 2 LAST CDS_LIB pure_quanta
J 0
(5450 -525);
DISPLAY INVISIBLE (5450 -525);
FORCEPROP 1 LAST PART_NUMBER CH5104KEB02
J 0
(5500 -675);
DISPLAY 0.510638 (5500 -675);
PAINT WHITE (5500 -675);
DISPLAY INVISIBLE (5500 -675);
FORCEPROP 1 LAST LOCATION C38
J 0
(5500 -425);
DISPLAY 0.702128 (5500 -425);
PAINT YELLOW (5500 -425);
FORCEPROP 1 LASTPIN (5450 -425) $PN 1
J 0
(5460 -445);
DISPLAY 0.808511 (5460 -445);
PAINT WHITE (5460 -445);
FORCEPROP 1 LASTPIN (5450 -625) $PN 2
J 0
(5460 -645);
DISPLAY 0.808511 (5460 -645);
PAINT WHITE (5460 -645);
FORCEPROP 2 LAST $SEC 1
J 0
(5500 -325);
DISPLAY 0.680851 (5500 -325);
PAINT MONO (5500 -325);
DISPLAY INVISIBLE (5500 -325);
FORCEPROP 0 LAST CDS_SEC 1
J 0
(5500 -325);
DISPLAY 0.680851 (5500 -325);
PAINT MONO (5500 -325);
DISPLAY INVISIBLE (5500 -325);
FORCEADD OFFPAGE..2
(5200 3425);
FORCEPROP 2 LAST $XR0 15 
J 0
(5389 3425);
DISPLAY 0.638298 (5389 3425);
PAINT MONO (5389 3425);
FORCEPROP 2 LAST PATH I366
J 0
(5400 3475);
DISPLAY 0.680851 (5400 3475);
DISPLAY INVISIBLE (5400 3475);
FORCEPROP 1 LAST COMMENT_BODY TRUE
J 0
(5155 3330);
DISPLAY 0.872340 (5155 3330);
PAINT PEACH (5155 3330);
DISPLAY INVISIBLE (5155 3330);
FORCEPROP 1 LAST OFFPAGE TRUE
J 0
(5525 3300);
DISPLAY 0.872340 (5525 3300);
PAINT GREEN (5525 3300);
DISPLAY INVISIBLE (5525 3300);
FORCEPROP 2 LAST CDS_LIB standard
J 0
(5200 3425);
DISPLAY INVISIBLE (5200 3425);
FORCEADD Q_RES..1
(4125 3425);
FORCEPROP 1 LAST VALUE 0
J 2
(4275 3425);
DISPLAY 0.510638 (4275 3425);
PAINT SKYBLUE (4275 3425);
FORCEPROP 1 LAST MATERIAL CHIP
J 0
(4300 3425);
DISPLAY 0.510638 (4300 3425);
PAINT SKYBLUE (4300 3425);
FORCEPROP 2 LAST CDS_LIB pure_quanta
J 0
(4125 3425);
DISPLAY INVISIBLE (4125 3425);
FORCEPROP 1 LAST PATH I367
J 0
(4075 3575);
DISPLAY 0.978723 (4075 3575);
PAINT WHITE (4075 3575);
DISPLAY INVISIBLE (4075 3575);
FORCEPROP 1 LAST PART_NUMBER CS00002JB13
J 0
(4025 3500);
DISPLAY 0.510638 (4025 3500);
PAINT WHITE (4025 3500);
DISPLAY INVISIBLE (4025 3500);
FORCEPROP 1 LAST WATTAGE 1/16W
J 2
(4475 3525);
DISPLAY 0.510638 (4475 3525);
PAINT SKYBLUE (4475 3525);
DISPLAY INVISIBLE (4475 3525);
FORCEPROP 1 LAST TOLERANCE 5%
J 0
(4050 3525);
DISPLAY 0.510638 (4050 3525);
PAINT SKYBLUE (4050 3525);
DISPLAY INVISIBLE (4050 3525);
FORCEPROP 1 LAST PACK_TYPE 0402LF
J 0
(4100 3475);
DISPLAY 0.510638 (4100 3475);
PAINT SKYBLUE (4100 3475);
DISPLAY INVISIBLE (4100 3475);
FORCEPROP 1 LAST $LOCATION R804
J 0
(3925 3425);
DISPLAY 0.702128 (3925 3425);
PAINT YELLOW (3925 3425);
FORCEPROP 1 LASTPIN (4025 3425) $PN 1
J 0
(4037 3437);
DISPLAY 0.787234 (4037 3437);
PAINT MONO (4037 3437);
FORCEPROP 1 LASTPIN (4225 3425) $PN 2
J 0
(4187 3437);
DISPLAY 0.787234 (4187 3437);
PAINT MONO (4187 3437);
FORCEPROP 0 LAST CDS_LOCATION R804
J 0
(3925 3475);
DISPLAY 0.680851 (3925 3475);
DISPLAY INVISIBLE (3925 3475);
FORCEPROP 0 LAST $SEC 1
J 0
(3925 3475);
DISPLAY 0.680851 (3925 3475);
PAINT MONO (3925 3475);
DISPLAY INVISIBLE (3925 3475);
FORCEPROP 0 LAST CDS_SEC 1
J 0
(3925 3475);
DISPLAY 0.680851 (3925 3475);
DISPLAY INVISIBLE (3925 3475);
FORCEADD Q_CAP..1
(3800 650);
FORCEPROP 1 LAST PART_NUMBER CH5474KE906
R 3
J 0
(3750 600);
DISPLAY 0.510638 (3750 600);
PAINT WHITE (3750 600);
FORCEPROP 1 LAST PACK_TYPE C0603
J 0
(3850 500);
DISPLAY 0.510638 (3850 500);
PAINT SKYBLUE (3850 500);
FORCEPROP 1 LAST MATERIAL X6S
J 0
(3850 550);
DISPLAY 0.510638 (3850 550);
PAINT SKYBLUE (3850 550);
FORCEPROP 1 LAST TOLERANCE 10%
J 0
(3850 600);
DISPLAY 0.510638 (3850 600);
PAINT SKYBLUE (3850 600);
FORCEPROP 1 LAST VOLTAGE 25V
J 0
(3850 650);
DISPLAY 0.510638 (3850 650);
PAINT SKYBLUE (3850 650);
FORCEPROP 1 LAST VALUE 4.7UF
J 0
(3850 700);
DISPLAY 0.510638 (3850 700);
PAINT SKYBLUE (3850 700);
FORCEPROP 1 LAST PATH I368
J 0
(3850 800);
DISPLAY 0.978723 (3850 800);
PAINT WHITE (3850 800);
DISPLAY INVISIBLE (3850 800);
FORCEPROP 2 LAST CDS_LIB pure_quanta
J 0
(3800 650);
DISPLAY INVISIBLE (3800 650);
FORCEPROP 1 LAST LOCATION C40
J 0
(3850 750);
DISPLAY 0.702128 (3850 750);
PAINT YELLOW (3850 750);
FORCEPROP 1 LASTPIN (3800 750) $PN 1
J 0
(3810 730);
DISPLAY 0.787234 (3810 730);
PAINT MONO (3810 730);
FORCEPROP 1 LASTPIN (3800 550) $PN 2
J 0
(3810 530);
DISPLAY 0.787234 (3810 530);
PAINT MONO (3810 530);
FORCEPROP 0 LAST $SEC 1
J 0
(3850 800);
DISPLAY 0.680851 (3850 800);
PAINT MONO (3850 800);
DISPLAY INVISIBLE (3850 800);
FORCEPROP 0 LAST CDS_SEC 1
J 0
(3850 800);
DISPLAY 0.680851 (3850 800);
DISPLAY INVISIBLE (3850 800);
FORCEADD Q_CAP..1
(5300 625);
FORCEPROP 1 LAST PACK_TYPE C0603
J 0
(5350 475);
DISPLAY 0.510638 (5350 475);
PAINT SKYBLUE (5350 475);
FORCEPROP 1 LAST VOLTAGE 25V
J 0
(5350 625);
DISPLAY 0.510638 (5350 625);
PAINT SKYBLUE (5350 625);
FORCEPROP 1 LAST VALUE 4.7UF
J 0
(5350 675);
DISPLAY 0.510638 (5350 675);
PAINT SKYBLUE (5350 675);
FORCEPROP 1 LAST TOLERANCE 10%
J 0
(5350 575);
DISPLAY 0.510638 (5350 575);
PAINT SKYBLUE (5350 575);
FORCEPROP 1 LAST MATERIAL X6S
J 0
(5350 525);
DISPLAY 0.510638 (5350 525);
PAINT SKYBLUE (5350 525);
FORCEPROP 1 LAST PART_NUMBER CH5474KE906
R 3
J 0
(5250 575);
DISPLAY 0.510638 (5250 575);
PAINT WHITE (5250 575);
FORCEPROP 1 LAST PATH I369
J 0
(5350 775);
DISPLAY 0.978723 (5350 775);
PAINT WHITE (5350 775);
DISPLAY INVISIBLE (5350 775);
FORCEPROP 2 LAST CDS_LIB pure_quanta
J 0
(5300 625);
DISPLAY INVISIBLE (5300 625);
FORCEPROP 1 LAST LOCATION C44
J 0
(5350 725);
DISPLAY 0.702128 (5350 725);
PAINT YELLOW (5350 725);
FORCEPROP 1 LASTPIN (5300 725) $PN 1
J 0
(5310 705);
DISPLAY 0.787234 (5310 705);
PAINT MONO (5310 705);
FORCEPROP 1 LASTPIN (5300 525) $PN 2
J 0
(5310 505);
DISPLAY 0.787234 (5310 505);
PAINT MONO (5310 505);
FORCEPROP 0 LAST $SEC 1
J 0
(5350 775);
DISPLAY 0.680851 (5350 775);
PAINT MONO (5350 775);
DISPLAY INVISIBLE (5350 775);
FORCEPROP 0 LAST CDS_SEC 1
J 0
(5350 775);
DISPLAY 0.680851 (5350 775);
DISPLAY INVISIBLE (5350 775);
FORCEADD Q_CAP..1
(5650 -525);
FORCEPROP 1 LAST PART_NUMBER CH4104K1B00
J 0
(5700 -725);
DISPLAY 0.510638 (5700 -725);
PAINT WHITE (5700 -725);
FORCEPROP 1 LAST PACK_TYPE 0402
J 0
(5700 -675);
DISPLAY 0.510638 (5700 -675);
PAINT SKYBLUE (5700 -675);
FORCEPROP 1 LAST TOLERANCE 10%
J 0
(5700 -575);
DISPLAY 0.510638 (5700 -575);
PAINT SKYBLUE (5700 -575);
FORCEPROP 1 LAST VOLTAGE 25V
J 0
(5700 -525);
DISPLAY 0.510638 (5700 -525);
PAINT SKYBLUE (5700 -525);
FORCEPROP 1 LAST VALUE 0.1UF
J 0
(5700 -475);
DISPLAY 0.510638 (5700 -475);
PAINT SKYBLUE (5700 -475);
FORCEPROP 1 LAST MATERIAL X7R
J 0
(5700 -625);
DISPLAY 0.510638 (5700 -625);
PAINT SKYBLUE (5700 -625);
FORCEPROP 1 LAST PATH I37
J 0
(5700 -375);
DISPLAY 0.978723 (5700 -375);
PAINT WHITE (5700 -375);
DISPLAY INVISIBLE (5700 -375);
FORCEPROP 2 LAST CDS_LIB pure_quanta
J 0
(5650 -525);
DISPLAY INVISIBLE (5650 -525);
FORCEPROP 1 LAST LOCATION C39
J 0
(5700 -425);
DISPLAY 0.702128 (5700 -425);
PAINT YELLOW (5700 -425);
FORCEPROP 1 LASTPIN (5650 -425) $PN 1
J 0
(5660 -445);
DISPLAY 0.808511 (5660 -445);
PAINT WHITE (5660 -445);
FORCEPROP 1 LASTPIN (5650 -625) $PN 2
J 0
(5660 -645);
DISPLAY 0.808511 (5660 -645);
PAINT WHITE (5660 -645);
FORCEPROP 2 LAST $SEC 1
J 0
(5700 -325);
DISPLAY 0.680851 (5700 -325);
PAINT MONO (5700 -325);
DISPLAY INVISIBLE (5700 -325);
FORCEPROP 0 LAST CDS_SEC 1
J 0
(5700 -325);
DISPLAY 0.680851 (5700 -325);
PAINT MONO (5700 -325);
DISPLAY INVISIBLE (5700 -325);
FORCEADD OFFPAGE..2
R 2
(-775 3775);
FORCEPROP 2 LAST $XR0 36 
J 0
(-1029 3775);
DISPLAY 0.638298 (-1029 3775);
PAINT MONO (-1029 3775);
FORCEPROP 2 LAST PATH I370
J 0
(-1025 3825);
DISPLAY 0.680851 (-1025 3825);
DISPLAY INVISIBLE (-1025 3825);
FORCEPROP 2 LAST CDS_LIB standard
J 0
(-775 3775);
DISPLAY INVISIBLE (-775 3775);
FORCEPROP 1 LAST OFFPAGE TRUE
J 2
(-1100 3650);
DISPLAY 0.872340 (-1100 3650);
PAINT GREEN (-1100 3650);
DISPLAY INVISIBLE (-1100 3650);
FORCEPROP 1 LAST COMMENT_BODY TRUE
J 2
(-730 3680);
DISPLAY 0.872340 (-730 3680);
PAINT PEACH (-730 3680);
DISPLAY INVISIBLE (-730 3680);
FORCEADD OFFPAGE..4
R 2
(-775 3875);
FORCEPROP 2 LAST $XR0 46 
J 0
(-996 3875);
DISPLAY 0.638298 (-996 3875);
PAINT MONO (-996 3875);
FORCEPROP 2 LAST $XR1 36 
J 0
(-1086 3875);
DISPLAY 0.638298 (-1086 3875);
PAINT MONO (-1086 3875);
FORCEPROP 1 LAST COMMENT_BODY TRUE
J 2
(-750 3775);
DISPLAY 0.872340 (-750 3775);
PAINT PEACH (-750 3775);
DISPLAY INVISIBLE (-750 3775);
FORCEPROP 1 LAST OFFPAGE TRUE
J 2
(-1100 3750);
DISPLAY 0.872340 (-1100 3750);
PAINT GREEN (-1100 3750);
DISPLAY INVISIBLE (-1100 3750);
FORCEPROP 2 LAST PATH I371
J 0
(-1025 3925);
DISPLAY 0.680851 (-1025 3925);
DISPLAY INVISIBLE (-1025 3925);
FORCEPROP 2 LAST CDS_LIB standard
J 0
(-775 3875);
DISPLAY INVISIBLE (-775 3875);
FORCEADD OFFPAGE..4
R 2
(-775 3825);
FORCEPROP 2 LAST $XR1 35 
J 0
(-1086 3825);
DISPLAY 0.638298 (-1086 3825);
PAINT MONO (-1086 3825);
FORCEPROP 2 LAST $XR0 28 
J 0
(-996 3825);
DISPLAY 0.638298 (-996 3825);
PAINT MONO (-996 3825);
FORCEPROP 2 LAST PATH I372
J 0
(-1025 3875);
DISPLAY 0.680851 (-1025 3875);
DISPLAY INVISIBLE (-1025 3875);
FORCEPROP 2 LAST CDS_LIB standard
J 0
(-775 3825);
DISPLAY INVISIBLE (-775 3825);
FORCEPROP 1 LAST COMMENT_BODY TRUE
J 2
(-750 3725);
DISPLAY 0.872340 (-750 3725);
PAINT PEACH (-750 3725);
DISPLAY INVISIBLE (-750 3725);
FORCEPROP 1 LAST OFFPAGE TRUE
J 2
(-1100 3700);
DISPLAY 0.872340 (-1100 3700);
PAINT GREEN (-1100 3700);
DISPLAY INVISIBLE (-1100 3700);
FORCEADD OFFPAGE..2
R 2
(-775 3725);
FORCEPROP 2 LAST $XR0 36 
J 0
(-1029 3725);
DISPLAY 0.638298 (-1029 3725);
PAINT MONO (-1029 3725);
FORCEPROP 2 LAST PATH I373
J 0
(-1025 3775);
DISPLAY 0.680851 (-1025 3775);
DISPLAY INVISIBLE (-1025 3775);
FORCEPROP 1 LAST COMMENT_BODY TRUE
J 2
(-730 3630);
DISPLAY 0.872340 (-730 3630);
PAINT PEACH (-730 3630);
DISPLAY INVISIBLE (-730 3630);
FORCEPROP 1 LAST OFFPAGE TRUE
J 2
(-1100 3600);
DISPLAY 0.872340 (-1100 3600);
PAINT GREEN (-1100 3600);
DISPLAY INVISIBLE (-1100 3600);
FORCEPROP 2 LAST CDS_LIB standard
J 0
(-775 3725);
DISPLAY INVISIBLE (-775 3725);
FORCEADD OFFPAGE..5
(-775 3675);
FORCEPROP 2 LAST $XR0 36 
J 0
(-1029 3675);
DISPLAY 0.638298 (-1029 3675);
PAINT MONO (-1029 3675);
FORCEPROP 2 LAST $XR1 10 
J 0
(-1119 3675);
DISPLAY 0.638298 (-1119 3675);
PAINT MONO (-1119 3675);
FORCEPROP 2 LAST CDS_LIB standard
J 0
(-775 3675);
DISPLAY INVISIBLE (-775 3675);
FORCEPROP 2 LAST PATH I378
J 0
(-725 3750);
DISPLAY 0.680851 (-725 3750);
DISPLAY INVISIBLE (-725 3750);
FORCEPROP 1 LAST OFFPAGE TRUE
J 0
(-450 3550);
DISPLAY 0.872340 (-450 3550);
DISPLAY INVISIBLE (-450 3550);
FORCEPROP 1 LAST COMMENT_BODY TRUE
J 0
(-675 3600);
DISPLAY 0.872340 (-675 3600);
PAINT GREEN (-675 3600);
DISPLAY INVISIBLE (-675 3600);
FORCEADD OFFPAGE..5
(-775 3575);
FORCEPROP 2 LAST $XR1 10 
J 0
(-1119 3575);
DISPLAY 0.638298 (-1119 3575);
PAINT MONO (-1119 3575);
FORCEPROP 2 LAST $XR0 36 
J 0
(-1029 3575);
DISPLAY 0.638298 (-1029 3575);
PAINT MONO (-1029 3575);
FORCEPROP 2 LAST CDS_LIB standard
J 0
(-775 3575);
DISPLAY INVISIBLE (-775 3575);
FORCEPROP 2 LAST PATH I379
J 0
(-725 3650);
DISPLAY 0.680851 (-725 3650);
DISPLAY INVISIBLE (-725 3650);
FORCEPROP 1 LAST COMMENT_BODY TRUE
J 0
(-675 3500);
DISPLAY 0.872340 (-675 3500);
PAINT GREEN (-675 3500);
DISPLAY INVISIBLE (-675 3500);
FORCEPROP 1 LAST OFFPAGE TRUE
J 0
(-450 3450);
DISPLAY 0.872340 (-450 3450);
DISPLAY INVISIBLE (-450 3450);
FORCEADD UNIVERSAL_POWER..1
(5900 -100);
FORCEPROP 3 LASTPIN (5900 -150) SIG_NAME P3V3_P1V8_SD2VDD\g
J 0
(5910 -140);
DISPLAY 0.659574 (5910 -140);
PAINT MONO (5910 -140);
DISPLAY INVISIBLE (5910 -140);
FORCEPROP 1 LAST HDL_POWER P3V3_P1V8_SD2VDD
J 1
(5900 -50);
DISPLAY 0.702128 (5900 -50);
PAINT GREEN (5900 -50);
FORCEPROP 1 LAST PATH I38
J 0
(5950 -75);
DISPLAY 0.872340 (5950 -75);
PAINT AQUA (5950 -75);
DISPLAY INVISIBLE (5950 -75);
FORCEPROP 2 LAST CDS_LIB logical_power
J 0
(5900 -100);
DISPLAY INVISIBLE (5900 -100);
FORCEADD OFFPAGE..4
(3375 3625);
FORCEPROP 2 LAST $XR0 46 
J 0
(3561 3625);
DISPLAY 0.638298 (3561 3625);
PAINT MONO (3561 3625);
FORCEPROP 2 LAST $XR1 34 
J 0
(3651 3625);
DISPLAY 0.638298 (3651 3625);
PAINT MONO (3651 3625);
FORCEPROP 2 LAST CDS_LIB standard
J 0
(3375 3625);
DISPLAY INVISIBLE (3375 3625);
FORCEPROP 2 LAST PATH I383
J 0
(3550 3700);
DISPLAY 0.680851 (3550 3700);
DISPLAY INVISIBLE (3550 3700);
FORCEPROP 1 LAST COMMENT_BODY TRUE
J 0
(3350 3525);
DISPLAY 1.574468 (3350 3525);
PAINT PEACH (3350 3525);
DISPLAY INVISIBLE (3350 3525);
FORCEPROP 1 LAST OFFPAGE TRUE
J 0
(3700 3500);
DISPLAY 1.574468 (3700 3500);
PAINT GREEN (3700 3500);
DISPLAY INVISIBLE (3700 3500);
FORCEADD OFFPAGE..6
(-675 2275);
FORCEPROP 2 LAST $XR0 26 
J 0
(-924 2275);
DISPLAY 0.638298 (-924 2275);
PAINT MONO (-924 2275);
FORCEPROP 2 LAST $XR1 27 
J 0
(-1014 2275);
DISPLAY 0.638298 (-1014 2275);
PAINT MONO (-1014 2275);
FORCEPROP 2 LAST $XR2 35 
J 0
(-1104 2275);
DISPLAY 0.638298 (-1104 2275);
PAINT MONO (-1104 2275);
FORCEPROP 2 LAST CDS_LIB standard
J 0
(-675 2275);
DISPLAY INVISIBLE (-675 2275);
FORCEPROP 2 LAST PATH I385
J 0
(-625 2350);
DISPLAY 0.680851 (-625 2350);
DISPLAY INVISIBLE (-625 2350);
FORCEPROP 1 LAST OFFPAGE TRUE
J 0
(-350 2150);
DISPLAY 0.872340 (-350 2150);
DISPLAY INVISIBLE (-350 2150);
FORCEPROP 1 LAST COMMENT_BODY TRUE
J 0
(-575 2200);
DISPLAY 0.872340 (-575 2200);
PAINT GREEN (-575 2200);
DISPLAY INVISIBLE (-575 2200);
FORCEADD OFFPAGE..3
(4125 1925);
FORCEPROP 2 LAST $XR0 10 
J 0
(4339 1925);
DISPLAY 0.638298 (4339 1925);
PAINT MONO (4339 1925);
FORCEPROP 1 LAST COMMENT_BODY TRUE
J 0
(4075 1825);
DISPLAY 0.872340 (4075 1825);
PAINT PEACH (4075 1825);
DISPLAY INVISIBLE (4075 1825);
FORCEPROP 1 LAST OFFPAGE TRUE
J 0
(4450 1800);
DISPLAY 0.872340 (4450 1800);
PAINT GREEN (4450 1800);
DISPLAY INVISIBLE (4450 1800);
FORCEPROP 2 LAST CDS_LIB standard
J 0
(4125 1925);
DISPLAY INVISIBLE (4125 1925);
FORCEPROP 2 LAST PATH I386
J 0
(4350 1975);
DISPLAY 0.680851 (4350 1975);
DISPLAY INVISIBLE (4350 1975);
FORCEADD Q_RES..1
(3200 1525);
FORCEPROP 1 LAST PACK_TYPE 0402LF
J 0
(3025 1500);
DISPLAY 0.510638 (3025 1500);
PAINT SKYBLUE (3025 1500);
FORCEPROP 1 LAST VALUE 0
J 2
(3350 1525);
DISPLAY 0.510638 (3350 1525);
PAINT SKYBLUE (3350 1525);
FORCEPROP 1 LAST MATERIAL CHIP
J 0
(3375 1525);
DISPLAY 0.510638 (3375 1525);
PAINT SKYBLUE (3375 1525);
FORCEPROP 1 LAST PART_NUMBER CS00002JB13
J 0
(3275 1500);
DISPLAY 0.510638 (3275 1500);
PAINT WHITE (3275 1500);
FORCEPROP 1 LAST TOLERANCE 5%
J 0
(3200 1425);
DISPLAY 0.510638 (3200 1425);
PAINT SKYBLUE (3200 1425);
DISPLAY INVISIBLE (3200 1425);
FORCEPROP 1 LAST WATTAGE 1/16W
J 2
(3175 1375);
DISPLAY 0.510638 (3175 1375);
PAINT SKYBLUE (3175 1375);
DISPLAY INVISIBLE (3175 1375);
FORCEPROP 2 LAST CDS_LIB pure_quanta
J 0
(3200 1525);
DISPLAY INVISIBLE (3200 1525);
FORCEPROP 1 LAST PATH I387
J 0
(3150 1675);
DISPLAY 0.978723 (3150 1675);
PAINT WHITE (3150 1675);
DISPLAY INVISIBLE (3150 1675);
FORCEPROP 1 LAST $LOCATION R853
J 0
(3000 1525);
DISPLAY 0.702128 (3000 1525);
PAINT YELLOW (3000 1525);
FORCEPROP 1 LASTPIN (3100 1525) $PN 1
J 0
(3112 1537);
DISPLAY 0.787234 (3112 1537);
PAINT MONO (3112 1537);
FORCEPROP 1 LASTPIN (3300 1525) $PN 2
J 0
(3262 1537);
DISPLAY 0.787234 (3262 1537);
PAINT MONO (3262 1537);
FORCEPROP 0 LAST CDS_LOCATION R853
J 0
(3075 1600);
DISPLAY 0.680851 (3075 1600);
DISPLAY INVISIBLE (3075 1600);
FORCEPROP 0 LAST $SEC 1
J 0
(3075 1600);
DISPLAY 0.680851 (3075 1600);
PAINT MONO (3075 1600);
DISPLAY INVISIBLE (3075 1600);
FORCEPROP 0 LAST CDS_SEC 1
J 0
(3075 1600);
DISPLAY 0.680851 (3075 1600);
DISPLAY INVISIBLE (3075 1600);
FORCEADD Q_RES..1
(3125 2325);
FORCEPROP 1 LAST MATERIAL CHIP
J 0
(3225 2325);
DISPLAY 0.510638 (3225 2325);
PAINT SKYBLUE (3225 2325);
FORCEPROP 1 LAST VALUE 49.9
J 2
(3025 2325);
DISPLAY 0.510638 (3025 2325);
PAINT SKYBLUE (3025 2325);
FORCEPROP 2 LAST CDS_LIB pure_quanta
J 0
(3125 2325);
DISPLAY INVISIBLE (3125 2325);
FORCEPROP 1 LAST PATH I389
J 0
(3075 2475);
DISPLAY 0.978723 (3075 2475);
PAINT WHITE (3075 2475);
DISPLAY INVISIBLE (3075 2475);
FORCEPROP 1 LAST TOLERANCE 1%
J 0
(3125 2225);
DISPLAY 0.510638 (3125 2225);
PAINT SKYBLUE (3125 2225);
DISPLAY INVISIBLE (3125 2225);
FORCEPROP 1 LAST PART_NUMBER CS04992FB07
J 0
(2600 2225);
DISPLAY 0.510638 (2600 2225);
PAINT WHITE (2600 2225);
DISPLAY INVISIBLE (2600 2225);
FORCEPROP 1 LAST PACK_TYPE 0402LF
J 0
(3200 2225);
DISPLAY 0.510638 (3200 2225);
PAINT SKYBLUE (3200 2225);
DISPLAY INVISIBLE (3200 2225);
FORCEPROP 1 LAST WATTAGE 1/16W
J 2
(3100 2175);
DISPLAY 0.510638 (3100 2175);
PAINT SKYBLUE (3100 2175);
DISPLAY INVISIBLE (3100 2175);
FORCEPROP 1 LAST LOCATION R216
J 0
(3075 2375);
DISPLAY 0.787234 (3075 2375);
FORCEPROP 1 LASTPIN (3025 2325) $PN 1
J 0
(3037 2337);
DISPLAY 0.787234 (3037 2337);
PAINT MONO (3037 2337);
FORCEPROP 1 LASTPIN (3225 2325) $PN 2
J 0
(3187 2337);
DISPLAY 0.787234 (3187 2337);
PAINT MONO (3187 2337);
FORCEPROP 0 LAST $SEC 1
J 0
(3075 2425);
DISPLAY 0.680851 (3075 2425);
PAINT MONO (3075 2425);
DISPLAY INVISIBLE (3075 2425);
FORCEPROP 0 LAST CDS_SEC 1
J 0
(3075 2425);
DISPLAY 0.680851 (3075 2425);
DISPLAY INVISIBLE (3075 2425);
FORCEADD OSC4_7X25000018..1
(575 450);
FORCEPROP 1 LAST MATERIAL MISC
J 0
(395 592);
DISPLAY 0.510638 (395 592);
PAINT SKYBLUE (395 592);
FORCEPROP 2 LAST PART_TYPE SMLF
J 0
(400 850);
DISPLAY 0.510638 (400 850);
PAINT SKYBLUE (400 850);
FORCEPROP 1 LAST PART_NUMBER BF625000023
J 0
(395 663);
DISPLAY 0.510638 (395 663);
PAINT WHITE (395 663);
FORCEPROP 2 LAST VALUE 25MHZ
J 0
(400 800);
DISPLAY 0.510638 (400 800);
PAINT SKYBLUE (400 800);
FORCEPROP 1 LAST PATH I39
J 0
(575 450);
DISPLAY 0.723404 (575 450);
PAINT GREEN (575 450);
DISPLAY INVISIBLE (575 450);
FORCEPROP 2 LAST CDS_LIB pure_quanta
J 0
(575 450);
DISPLAY INVISIBLE (575 450);
FORCEPROP 1 LAST PIN_NAMES_ROTATE True
J 0
(575 450);
DISPLAY 0.489362 (575 450);
PAINT GREEN (575 450);
DISPLAY INVISIBLE (575 450);
FORCEPROP 1 LAST CDS_LMAN_SYM_OUTLINE -175,125,175,-125
J 0
(575 450);
DISPLAY 0.468085 (575 450);
PAINT GREEN (575 450);
DISPLAY INVISIBLE (575 450);
FORCEPROP 1 LAST LOCATION OSC1
J 0
(395 741);
DISPLAY 0.702128 (395 741);
PAINT YELLOW (395 741);
FORCEPROP 2 LASTPIN (900 375) $PN 2
J 0
(910 385);
DISPLAY 0.808511 (910 385);
PAINT WHITE (910 385);
FORCEPROP 2 LASTPIN (250 375) $PN 1
J 2
(240 385);
DISPLAY 0.808511 (240 385);
PAINT WHITE (240 385);
FORCEPROP 2 LASTPIN (900 525) $PN 3
J 0
(910 535);
DISPLAY 0.808511 (910 535);
PAINT WHITE (910 535);
FORCEPROP 2 LASTPIN (250 525) $PN 4
J 2
(240 535);
DISPLAY 0.808511 (240 535);
PAINT WHITE (240 535);
FORCEPROP 2 LAST $SEC 1
J 0
(400 875);
DISPLAY 0.680851 (400 875);
PAINT MONO (400 875);
DISPLAY INVISIBLE (400 875);
FORCEPROP 0 LAST CDS_SEC 1
J 0
(400 875);
DISPLAY 0.680851 (400 875);
PAINT MONO (400 875);
DISPLAY INVISIBLE (400 875);
FORCEADD OFFPAGE..2
(5575 3900);
FORCEPROP 2 LAST CDS_LIB standard
J 0
(5575 3900);
DISPLAY INVISIBLE (5575 3900);
FORCEPROP 2 LAST PATH I390
J 0
(5750 3975);
DISPLAY 0.680851 (5750 3975);
DISPLAY INVISIBLE (5750 3975);
FORCEPROP 1 LAST COMMENT_BODY TRUE
J 0
(5530 3805);
DISPLAY 0.872340 (5530 3805);
PAINT PEACH (5530 3805);
DISPLAY INVISIBLE (5530 3805);
FORCEPROP 1 LAST OFFPAGE TRUE
J 0
(5900 3775);
DISPLAY 0.872340 (5900 3775);
PAINT GREEN (5900 3775);
DISPLAY INVISIBLE (5900 3775);
FORCEADD Q_RES..1
(4425 3900);
FORCEPROP 1 LAST MATERIAL CHIP
J 0
(4650 3900);
DISPLAY 0.510638 (4650 3900);
PAINT SKYBLUE (4650 3900);
FORCEPROP 1 LAST VALUE 4.7K
J 2
(4625 3900);
DISPLAY 0.510638 (4625 3900);
PAINT SKYBLUE (4625 3900);
FORCEPROP 2 LAST CDS_LIB pure_quanta
J 0
(4425 3900);
DISPLAY INVISIBLE (4425 3900);
FORCEPROP 1 LAST PATH I391
J 0
(4375 4050);
DISPLAY 0.978723 (4375 4050);
PAINT WHITE (4375 4050);
DISPLAY INVISIBLE (4375 4050);
FORCEPROP 1 LAST PART_NUMBER CS24702FB06
J 0
(4375 4000);
DISPLAY 0.510638 (4375 4000);
PAINT WHITE (4375 4000);
DISPLAY INVISIBLE (4375 4000);
FORCEPROP 1 LAST WATTAGE 1/16W
J 2
(4400 3750);
DISPLAY 0.510638 (4400 3750);
PAINT SKYBLUE (4400 3750);
DISPLAY INVISIBLE (4400 3750);
FORCEPROP 1 LAST TOLERANCE 1%
J 0
(4425 3800);
DISPLAY 0.510638 (4425 3800);
PAINT SKYBLUE (4425 3800);
DISPLAY INVISIBLE (4425 3800);
FORCEPROP 1 LAST PACK_TYPE 0402LF
J 0
(4675 3750);
DISPLAY 0.510638 (4675 3750);
PAINT SKYBLUE (4675 3750);
DISPLAY INVISIBLE (4675 3750);
FORCEPROP 1 LAST $LOCATION R462
J 2
(4350 3900);
DISPLAY 0.702128 (4350 3900);
PAINT YELLOW (4350 3900);
FORCEPROP 1 LASTPIN (4325 3900) $PN 1
J 0
(4337 3912);
DISPLAY 0.787234 (4337 3912);
PAINT MONO (4337 3912);
FORCEPROP 1 LASTPIN (4525 3900) $PN 2
J 0
(4487 3912);
DISPLAY 0.787234 (4487 3912);
PAINT MONO (4487 3912);
FORCEPROP 0 LAST CDS_LOCATION R462
J 0
(4350 3950);
DISPLAY 0.680851 (4350 3950);
DISPLAY INVISIBLE (4350 3950);
FORCEPROP 0 LAST $SEC 1
J 0
(4350 3950);
DISPLAY 0.680851 (4350 3950);
PAINT MONO (4350 3950);
DISPLAY INVISIBLE (4350 3950);
FORCEPROP 0 LAST CDS_SEC 1
J 0
(4350 3950);
DISPLAY 0.680851 (4350 3950);
DISPLAY INVISIBLE (4350 3950);
FORCEADD OFFPAGE..2
(3825 3650);
FORCEPROP 1 LAST COMMENT_BODY TRUE
J 0
(3780 3555);
DISPLAY 0.872340 (3780 3555);
PAINT PEACH (3780 3555);
DISPLAY INVISIBLE (3780 3555);
FORCEPROP 1 LAST OFFPAGE TRUE
J 0
(4150 3525);
DISPLAY 0.872340 (4150 3525);
PAINT GREEN (4150 3525);
DISPLAY INVISIBLE (4150 3525);
FORCEPROP 2 LAST PATH I392
J 0
(4000 3725);
DISPLAY 0.680851 (4000 3725);
DISPLAY INVISIBLE (4000 3725);
FORCEPROP 2 LAST CDS_LIB standard
J 0
(3825 3650);
DISPLAY INVISIBLE (3825 3650);
FORCEADD 74LVC1G08GW..1
(5225 1625);
FORCEPROP 1 LAST PART_NUMBER ALVC1G08009
J 0
(5375 1485);
DISPLAY 0.723404 (5375 1485);
PAINT GREEN (5375 1485);
FORCEPROP 1 LAST MATERIAL IC
J 0
(5375 1435);
DISPLAY 0.723404 (5375 1435);
PAINT GREEN (5375 1435);
FORCEPROP 2 LAST VALUE 74LVC1G08GW
J 0
(5275 1750);
DISPLAY 0.680851 (5275 1750);
FORCEPROP 0 LAST PACK_TYPE SM
J 0
(5375 1575);
DISPLAY 0.680851 (5375 1575);
DISPLAY INVISIBLE (5375 1575);
FORCEPROP 1 LAST NEEDS_NO_SIZE TRUE
J 0
(5225 1625);
DISPLAY 0.468085 (5225 1625);
PAINT GREEN (5225 1625);
DISPLAY INVISIBLE (5225 1625);
FORCEPROP 1 LAST PATH I393
J 0
(5500 1430);
DISPLAY 0.723404 (5500 1430);
PAINT GREEN (5500 1430);
DISPLAY INVISIBLE (5500 1430);
FORCEPROP 2 LAST CDS_LIB pure_quanta
J 0
(5225 1625);
DISPLAY INVISIBLE (5225 1625);
FORCEPROP 1 LAST $LOCATION U15
J 0
(5375 1530);
DISPLAY 0.723404 (5375 1530);
PAINT GREEN (5375 1530);
FORCEPROP 0 LASTPIN (4925 1575) $PN 2
J 2
(4915 1585);
DISPLAY 0.680851 (4915 1585);
PAINT MONO (4915 1585);
FORCEPROP 0 LASTPIN (4925 1675) $PN 1
J 2
(4915 1685);
DISPLAY 0.680851 (4915 1685);
PAINT MONO (4915 1685);
FORCEPROP 0 LASTPIN (5175 1375) $PN 3
R 1
J 2
(5165 1365);
DISPLAY 0.680851 (5165 1365);
PAINT MONO (5165 1365);
FORCEPROP 0 LASTPIN (5175 1875) $PN 5
R 1
J 0
(5165 1885);
DISPLAY 0.680851 (5165 1885);
PAINT MONO (5165 1885);
FORCEPROP 0 LASTPIN (5525 1625) $PN 4
J 0
(5535 1635);
DISPLAY 0.680851 (5535 1635);
PAINT MONO (5535 1635);
FORCEPROP 0 LAST CDS_LOCATION U15
J 0
(5275 1800);
DISPLAY 0.680851 (5275 1800);
DISPLAY INVISIBLE (5275 1800);
FORCEPROP 0 LAST $SEC 1
J 0
(5275 1800);
DISPLAY 0.680851 (5275 1800);
PAINT MONO (5275 1800);
DISPLAY INVISIBLE (5275 1800);
FORCEPROP 0 LAST CDS_SEC 1
J 0
(5275 1800);
DISPLAY 0.680851 (5275 1800);
DISPLAY INVISIBLE (5275 1800);
FORCEADD OFFPAGE..1
(4075 1575);
FORCEPROP 1 LAST COMMENT_BODY TRUE
J 0
(4200 1475);
DISPLAY 0.872340 (4200 1475);
PAINT PEACH (4200 1475);
DISPLAY INVISIBLE (4200 1475);
FORCEPROP 1 LAST OFFPAGE TRUE
J 0
(4400 1450);
DISPLAY 0.872340 (4400 1450);
PAINT GREEN (4400 1450);
DISPLAY INVISIBLE (4400 1450);
FORCEPROP 2 LAST PATH I395
J 0
(4125 1650);
DISPLAY 0.680851 (4125 1650);
DISPLAY INVISIBLE (4125 1650);
FORCEPROP 2 LAST CDS_LIB standard
J 0
(4075 1575);
DISPLAY INVISIBLE (4075 1575);
FORCEADD UNIVERSAL_GND..1
(5575 1850);
FORCEPROP 3 LASTPIN (5575 1900) SIG_NAME GND\g
J 0
(5585 1910);
DISPLAY 0.659574 (5585 1910);
PAINT MONO (5585 1910);
DISPLAY INVISIBLE (5585 1910);
FORCEPROP 2 LAST CDS_LIB logical_power
J 0
(5575 1850);
DISPLAY INVISIBLE (5575 1850);
FORCEPROP 1 LAST PATH I396
J 0
(5650 1850);
DISPLAY 0.872340 (5650 1850);
PAINT AQUA (5650 1850);
DISPLAY INVISIBLE (5650 1850);
FORCEPROP 1 LAST HDL_POWER GND
J 1
(5600 1775);
DISPLAY 0.702128 (5600 1775);
PAINT GREEN (5600 1775);
DISPLAY INVISIBLE (5600 1775);
FORCEADD VCCAUX15..1
(5175 2275);
FORCEPROP 3 LASTPIN (5175 2225) SIG_NAME P3V3_AUX\g
J 0
(5185 2235);
DISPLAY 0.659574 (5185 2235);
PAINT MONO (5185 2235);
DISPLAY INVISIBLE (5185 2235);
FORCEPROP 1 LAST HDL_POWER P3V3_AUX
J 1
(5175 2325);
DISPLAY 0.702128 (5175 2325);
PAINT GREEN (5175 2325);
FORCEPROP 1 LAST PATH I397
J 0
(5225 2300);
DISPLAY 0.872340 (5225 2300);
PAINT AQUA (5225 2300);
DISPLAY INVISIBLE (5225 2300);
FORCEPROP 2 LAST CDS_LIB logical_power
J 0
(5175 2275);
DISPLAY INVISIBLE (5175 2275);
FORCEADD Q_CAP..1
R 2
(5575 2025);
FORCEPROP 1 LAST TOLERANCE 10%
J 2
(5525 1950);
DISPLAY 0.510638 (5525 1950);
PAINT SKYBLUE (5525 1950);
FORCEPROP 1 LAST VOLTAGE 25V
J 2
(5525 2000);
DISPLAY 0.510638 (5525 2000);
PAINT SKYBLUE (5525 2000);
FORCEPROP 1 LAST PACK_TYPE 0402
J 2
(5525 1850);
DISPLAY 0.510638 (5525 1850);
PAINT SKYBLUE (5525 1850);
FORCEPROP 1 LAST MATERIAL X7R
J 2
(5525 1900);
DISPLAY 0.510638 (5525 1900);
PAINT SKYBLUE (5525 1900);
FORCEPROP 1 LAST PART_NUMBER CH4104K1B00
J 2
(5525 1800);
DISPLAY 0.510638 (5525 1800);
PAINT WHITE (5525 1800);
FORCEPROP 1 LAST VALUE 0.1UF
J 2
(5525 2050);
DISPLAY 0.510638 (5525 2050);
PAINT SKYBLUE (5525 2050);
FORCEPROP 1 LAST PATH I398
J 2
(5525 2175);
DISPLAY 0.978723 (5525 2175);
PAINT WHITE (5525 2175);
DISPLAY INVISIBLE (5525 2175);
FORCEPROP 2 LAST CDS_LIB pure_quanta
J 0
(5575 2025);
DISPLAY INVISIBLE (5575 2025);
FORCEPROP 1 LAST $LOCATION C26
J 2
(5525 2100);
DISPLAY 0.978723 (5525 2100);
FORCEPROP 1 LASTPIN (5575 2125) $PN 1
J 2
(5565 2105);
DISPLAY 0.787234 (5565 2105);
PAINT MONO (5565 2105);
FORCEPROP 1 LASTPIN (5575 1925) $PN 2
J 2
(5565 1905);
DISPLAY 0.787234 (5565 1905);
PAINT MONO (5565 1905);
FORCEPROP 0 LAST CDS_LOCATION C26
J 0
(5525 2175);
DISPLAY 0.680851 (5525 2175);
DISPLAY INVISIBLE (5525 2175);
FORCEPROP 0 LAST $SEC 1
J 0
(5525 2175);
DISPLAY 0.680851 (5525 2175);
PAINT MONO (5525 2175);
DISPLAY INVISIBLE (5525 2175);
FORCEPROP 0 LAST CDS_SEC 1
J 0
(5525 2175);
DISPLAY 0.680851 (5525 2175);
DISPLAY INVISIBLE (5525 2175);
FORCEADD UNIVERSAL_GND..1
(5175 1275);
FORCEPROP 3 LASTPIN (5175 1325) SIG_NAME GND\g
J 0
(5185 1335);
DISPLAY 0.659574 (5185 1335);
PAINT MONO (5185 1335);
DISPLAY INVISIBLE (5185 1335);
FORCEPROP 2 LAST CDS_LIB logical_power
J 0
(5175 1275);
DISPLAY INVISIBLE (5175 1275);
FORCEPROP 1 LAST PATH I399
J 0
(5250 1275);
DISPLAY 0.872340 (5250 1275);
PAINT AQUA (5250 1275);
DISPLAY INVISIBLE (5250 1275);
FORCEPROP 1 LAST HDL_POWER GND
J 1
(5200 1200);
DISPLAY 0.702128 (5200 1200);
PAINT GREEN (5200 1200);
DISPLAY INVISIBLE (5200 1200);
FORCEADD Q_RES..1
(2425 -550);
FORCEPROP 1 LAST WATTAGE 1/16W
J 2
(2500 -450);
DISPLAY 0.510638 (2500 -450);
PAINT SKYBLUE (2500 -450);
FORCEPROP 1 LAST MATERIAL CHIP
J 0
(2525 -450);
DISPLAY 0.510638 (2525 -450);
PAINT SKYBLUE (2525 -450);
FORCEPROP 1 LAST PART_NUMBER CS00002JB13
J 0
(2375 -375);
DISPLAY 0.510638 (2375 -375);
PAINT WHITE (2375 -375);
FORCEPROP 1 LAST VALUE 0
J 2
(2600 -550);
DISPLAY 0.510638 (2600 -550);
PAINT SKYBLUE (2600 -550);
FORCEPROP 1 LAST PACK_TYPE 0402LF
J 0
(2725 -450);
DISPLAY 0.510638 (2725 -450);
PAINT SKYBLUE (2725 -450);
FORCEPROP 1 LAST TOLERANCE 5%
J 0
(3000 -450);
DISPLAY 0.510638 (3000 -450);
PAINT SKYBLUE (3000 -450);
FORCEPROP 1 LAST PATH I4
J 0
(2375 -400);
DISPLAY 0.978723 (2375 -400);
PAINT WHITE (2375 -400);
DISPLAY INVISIBLE (2375 -400);
FORCEPROP 2 LAST CDS_LIB pure_quanta
J 0
(2425 -550);
DISPLAY INVISIBLE (2425 -550);
FORCEPROP 1 LAST LOCATION R207
J 0
(2200 -550);
DISPLAY 0.702128 (2200 -550);
PAINT YELLOW (2200 -550);
FORCEPROP 1 LASTPIN (2325 -550) $PN 1
J 0
(2337 -538);
DISPLAY 0.808511 (2337 -538);
PAINT WHITE (2337 -538);
FORCEPROP 1 LASTPIN (2525 -550) $PN 2
J 0
(2487 -538);
DISPLAY 0.808511 (2487 -538);
PAINT WHITE (2487 -538);
FORCEPROP 2 LAST $SEC 1
J 0
(2375 -325);
DISPLAY 0.680851 (2375 -325);
PAINT MONO (2375 -325);
DISPLAY INVISIBLE (2375 -325);
FORCEPROP 0 LAST CDS_SEC 1
J 0
(2375 -325);
DISPLAY 0.680851 (2375 -325);
PAINT MONO (2375 -325);
DISPLAY INVISIBLE (2375 -325);
FORCEADD UNIVERSAL_GND..1
(1075 175);
FORCEPROP 3 LASTPIN (1075 225) SIG_NAME GND\g
J 0
(1085 235);
DISPLAY 0.659574 (1085 235);
PAINT MONO (1085 235);
DISPLAY INVISIBLE (1085 235);
FORCEPROP 1 LAST PATH I40
J 0
(1150 175);
DISPLAY 0.872340 (1150 175);
PAINT AQUA (1150 175);
DISPLAY INVISIBLE (1150 175);
FORCEPROP 1 LAST HDL_POWER GND
J 1
(1100 100);
DISPLAY 0.702128 (1100 100);
PAINT GREEN (1100 100);
DISPLAY INVISIBLE (1100 100);
FORCEPROP 2 LAST CDS_LIB logical_power
J 0
(1075 175);
DISPLAY INVISIBLE (1075 175);
FORCEADD OFFPAGE..2
(6050 1625);
FORCEPROP 2 LAST $XR0 11 
J 0
(6239 1625);
DISPLAY 0.638298 (6239 1625);
PAINT MONO (6239 1625);
FORCEPROP 2 LAST $XR1 10 
J 0
(6329 1625);
DISPLAY 0.638298 (6329 1625);
PAINT MONO (6329 1625);
FORCEPROP 2 LAST CDS_LIB standard
J 0
(6050 1625);
DISPLAY INVISIBLE (6050 1625);
FORCEPROP 1 LAST OFFPAGE TRUE
J 0
(6375 1500);
DISPLAY 0.872340 (6375 1500);
PAINT GREEN (6375 1500);
DISPLAY INVISIBLE (6375 1500);
FORCEPROP 1 LAST COMMENT_BODY TRUE
J 0
(6005 1530);
DISPLAY 0.872340 (6005 1530);
PAINT PEACH (6005 1530);
DISPLAY INVISIBLE (6005 1530);
FORCEPROP 2 LAST PATH I400
J 0
(6350 1675);
DISPLAY 0.680851 (6350 1675);
DISPLAY INVISIBLE (6350 1675);
FORCEADD OFFPAGE..1
(4075 1675);
FORCEPROP 2 LAST $XR0 15 
J 0
(3824 1675);
DISPLAY 0.638298 (3824 1675);
PAINT MONO (3824 1675);
FORCEPROP 2 LAST PATH I401
J 0
(3825 1725);
DISPLAY 0.680851 (3825 1725);
DISPLAY INVISIBLE (3825 1725);
FORCEPROP 2 LAST CDS_LIB standard
J 0
(4075 1675);
DISPLAY INVISIBLE (4075 1675);
FORCEPROP 1 LAST OFFPAGE TRUE
J 0
(4400 1550);
DISPLAY 0.872340 (4400 1550);
PAINT GREEN (4400 1550);
DISPLAY INVISIBLE (4400 1550);
FORCEPROP 1 LAST COMMENT_BODY TRUE
J 0
(4200 1575);
DISPLAY 0.872340 (4200 1575);
PAINT PEACH (4200 1575);
DISPLAY INVISIBLE (4200 1575);
FORCEADD Q_RES..1
(-725 4025);
FORCEPROP 1 LAST MATERIAL CHIP
J 0
(-625 4000);
DISPLAY 0.510638 (-625 4000);
PAINT SKYBLUE (-625 4000);
FORCEPROP 1 LAST VALUE 33.2
J 2
(-525 4025);
DISPLAY 0.510638 (-525 4025);
PAINT SKYBLUE (-525 4025);
FORCEPROP 1 LAST WATTAGE 1/16W
J 2
(-750 3875);
DISPLAY 0.510638 (-750 3875);
PAINT SKYBLUE (-750 3875);
DISPLAY INVISIBLE (-750 3875);
FORCEPROP 1 LAST PACK_TYPE 0402LF
J 0
(-475 3875);
DISPLAY 0.510638 (-475 3875);
PAINT SKYBLUE (-475 3875);
DISPLAY INVISIBLE (-475 3875);
FORCEPROP 1 LAST PART_NUMBER CS03322FB03
J 0
(-775 4125);
DISPLAY 0.510638 (-775 4125);
PAINT WHITE (-775 4125);
DISPLAY INVISIBLE (-775 4125);
FORCEPROP 1 LAST TOLERANCE 1%
J 0
(-725 3925);
DISPLAY 0.510638 (-725 3925);
PAINT SKYBLUE (-725 3925);
DISPLAY INVISIBLE (-725 3925);
FORCEPROP 1 LAST PATH I404
J 0
(-775 4175);
DISPLAY 0.978723 (-775 4175);
PAINT WHITE (-775 4175);
DISPLAY INVISIBLE (-775 4175);
FORCEPROP 2 LAST CDS_LIB pure_quanta
J 0
(-725 4025);
DISPLAY INVISIBLE (-725 4025);
FORCEPROP 1 LAST LOCATION R585
J 0
(-875 4025);
DISPLAY 0.702128 (-875 4025);
PAINT YELLOW (-875 4025);
FORCEPROP 1 LASTPIN (-825 4025) $PN 1
J 0
(-813 4037);
DISPLAY 0.787234 (-813 4037);
PAINT MONO (-813 4037);
FORCEPROP 1 LASTPIN (-625 4025) $PN 2
J 0
(-663 4037);
DISPLAY 0.787234 (-663 4037);
PAINT MONO (-663 4037);
FORCEPROP 0 LAST $SEC 1
J 0
(-875 4075);
DISPLAY 0.680851 (-875 4075);
PAINT MONO (-875 4075);
DISPLAY INVISIBLE (-875 4075);
FORCEPROP 0 LAST CDS_SEC 1
J 0
(-875 4075);
DISPLAY 0.680851 (-875 4075);
DISPLAY INVISIBLE (-875 4075);
FORCEADD Q_RES..1
(4100 3550);
FORCEPROP 1 LAST VALUE 100
J 0
(4200 3550);
DISPLAY 0.510638 (4200 3550);
PAINT SKYBLUE (4200 3550);
FORCEPROP 1 LAST MATERIAL CHIP
J 0
(4300 3550);
DISPLAY 0.510638 (4300 3550);
PAINT SKYBLUE (4300 3550);
FORCEPROP 1 LAST PART_NUMBER CS11002FB07
J 0
(3975 3600);
DISPLAY 0.510638 (3975 3600);
PAINT WHITE (3975 3600);
FORCEPROP 2 LAST CDS_LIB pure_quanta
J 0
(4100 3550);
DISPLAY INVISIBLE (4100 3550);
FORCEPROP 1 LAST PATH I405
J 0
(4050 3700);
DISPLAY 0.978723 (4050 3700);
PAINT WHITE (4050 3700);
DISPLAY INVISIBLE (4050 3700);
FORCEPROP 1 LAST WATTAGE 1/16W
J 2
(3750 3450);
DISPLAY 0.510638 (3750 3450);
PAINT SKYBLUE (3750 3450);
DISPLAY INVISIBLE (3750 3450);
FORCEPROP 1 LAST TOLERANCE 1%
J 0
(4125 3450);
DISPLAY 0.510638 (4125 3450);
PAINT SKYBLUE (4125 3450);
DISPLAY INVISIBLE (4125 3450);
FORCEPROP 1 LAST PACK_TYPE 0402LF
J 0
(3925 3450);
DISPLAY 0.510638 (3925 3450);
PAINT SKYBLUE (3925 3450);
DISPLAY INVISIBLE (3925 3450);
FORCEPROP 1 LAST LOCATION R225
J 0
(3900 3550);
DISPLAY 0.702128 (3900 3550);
PAINT YELLOW (3900 3550);
FORCEPROP 1 LASTPIN (4000 3550) $PN 1
J 0
(4012 3562);
DISPLAY 0.787234 (4012 3562);
PAINT MONO (4012 3562);
FORCEPROP 1 LASTPIN (4200 3550) $PN 2
J 0
(4162 3562);
DISPLAY 0.787234 (4162 3562);
PAINT MONO (4162 3562);
FORCEPROP 0 LAST $SEC 1
J 0
(3975 3625);
DISPLAY 0.680851 (3975 3625);
PAINT MONO (3975 3625);
DISPLAY INVISIBLE (3975 3625);
FORCEPROP 0 LAST CDS_SEC 1
J 0
(3975 3625);
DISPLAY 0.680851 (3975 3625);
DISPLAY INVISIBLE (3975 3625);
FORCEADD Q_RES..1
(4125 3375);
FORCEPROP 1 LAST VALUE 100
J 0
(4225 3375);
DISPLAY 0.510638 (4225 3375);
PAINT SKYBLUE (4225 3375);
FORCEPROP 1 LAST MATERIAL CHIP
J 0
(4325 3375);
DISPLAY 0.510638 (4325 3375);
PAINT SKYBLUE (4325 3375);
FORCEPROP 1 LAST PART_NUMBER CS11002FB07
J 0
(3650 3375);
DISPLAY 0.510638 (3650 3375);
PAINT WHITE (3650 3375);
FORCEPROP 1 LAST WATTAGE 1/16W
J 2
(3775 3275);
DISPLAY 0.510638 (3775 3275);
PAINT SKYBLUE (3775 3275);
DISPLAY INVISIBLE (3775 3275);
FORCEPROP 1 LAST TOLERANCE 1%
J 0
(4150 3275);
DISPLAY 0.510638 (4150 3275);
PAINT SKYBLUE (4150 3275);
DISPLAY INVISIBLE (4150 3275);
FORCEPROP 1 LAST PACK_TYPE 0402LF
J 0
(3950 3275);
DISPLAY 0.510638 (3950 3275);
PAINT SKYBLUE (3950 3275);
DISPLAY INVISIBLE (3950 3275);
FORCEPROP 1 LAST PATH I406
J 0
(4075 3525);
DISPLAY 0.978723 (4075 3525);
PAINT WHITE (4075 3525);
DISPLAY INVISIBLE (4075 3525);
FORCEPROP 2 LAST CDS_LIB pure_quanta
J 0
(4125 3375);
DISPLAY INVISIBLE (4125 3375);
FORCEPROP 1 LAST LOCATION R565
J 0
(3925 3375);
DISPLAY 0.702128 (3925 3375);
PAINT YELLOW (3925 3375);
FORCEPROP 1 LASTPIN (4025 3375) $PN 1
J 0
(4037 3387);
DISPLAY 0.787234 (4037 3387);
PAINT MONO (4037 3387);
FORCEPROP 1 LASTPIN (4225 3375) $PN 2
J 0
(4187 3387);
DISPLAY 0.787234 (4187 3387);
PAINT MONO (4187 3387);
FORCEPROP 0 LAST $SEC 1
J 0
(3925 3425);
DISPLAY 0.680851 (3925 3425);
PAINT MONO (3925 3425);
DISPLAY INVISIBLE (3925 3425);
FORCEPROP 0 LAST CDS_SEC 1
J 0
(3925 3425);
DISPLAY 0.680851 (3925 3425);
DISPLAY INVISIBLE (3925 3425);
FORCEADD Q_RES..1
(1750 525);
FORCEPROP 1 LAST PACK_TYPE 0402LF
J 0
(1850 450);
DISPLAY 0.510638 (1850 450);
PAINT SKYBLUE (1850 450);
FORCEPROP 1 LAST MATERIAL CHIP
J 0
(1700 450);
DISPLAY 0.510638 (1700 450);
PAINT SKYBLUE (1700 450);
FORCEPROP 1 LAST TOLERANCE 1%
J 0
(1950 400);
DISPLAY 0.510638 (1950 400);
PAINT SKYBLUE (1950 400);
FORCEPROP 1 LAST PART_NUMBER CS03322FB03
J 0
(1600 400);
DISPLAY 0.510638 (1600 400);
PAINT WHITE (1600 400);
FORCEPROP 1 LAST VALUE 33.2
J 2
(1950 525);
DISPLAY 0.510638 (1950 525);
PAINT SKYBLUE (1950 525);
FORCEPROP 1 LAST WATTAGE 1/16W
J 2
(1675 450);
DISPLAY 0.510638 (1675 450);
PAINT SKYBLUE (1675 450);
FORCEPROP 1 LAST PATH I42
J 0
(1700 675);
DISPLAY 0.978723 (1700 675);
PAINT WHITE (1700 675);
DISPLAY INVISIBLE (1700 675);
FORCEPROP 2 LAST CDS_LIB pure_quanta
J 0
(1750 525);
DISPLAY INVISIBLE (1750 525);
FORCEPROP 1 LAST LOCATION R215
J 0
(1525 525);
DISPLAY 0.702128 (1525 525);
PAINT YELLOW (1525 525);
FORCEPROP 1 LASTPIN (1650 525) $PN 1
J 0
(1662 537);
DISPLAY 0.808511 (1662 537);
PAINT WHITE (1662 537);
FORCEPROP 1 LASTPIN (1850 525) $PN 2
J 0
(1812 537);
DISPLAY 0.808511 (1812 537);
PAINT WHITE (1812 537);
FORCEPROP 2 LAST $SEC 1
J 0
(1700 725);
DISPLAY 0.680851 (1700 725);
PAINT MONO (1700 725);
DISPLAY INVISIBLE (1700 725);
FORCEPROP 0 LAST CDS_SEC 1
J 0
(1700 725);
DISPLAY 0.680851 (1700 725);
PAINT MONO (1700 725);
DISPLAY INVISIBLE (1700 725);
FORCEADD UNIVERSAL_GND..1
(-2250 3825);
FORCEPROP 3 LASTPIN (-2250 3875) SIG_NAME GND\g
J 0
(-2240 3885);
DISPLAY 0.659574 (-2240 3885);
PAINT MONO (-2240 3885);
DISPLAY INVISIBLE (-2240 3885);
FORCEPROP 1 LAST PATH I46
J 0
(-2175 3825);
DISPLAY 0.872340 (-2175 3825);
PAINT AQUA (-2175 3825);
DISPLAY INVISIBLE (-2175 3825);
FORCEPROP 1 LAST HDL_POWER GND
J 1
(-2266 3791);
DISPLAY 0.702128 (-2266 3791);
PAINT GREEN (-2266 3791);
DISPLAY INVISIBLE (-2266 3791);
FORCEPROP 2 LAST CDS_LIB logical_power
J 0
(-2297 3872);
DISPLAY INVISIBLE (-2297 3872);
FORCEADD Q_RES..1
(-1850 3975);
FORCEPROP 1 LAST PART_NUMBER CS21002FB06
J 0
(-2150 3925);
DISPLAY 0.510638 (-2150 3925);
PAINT WHITE (-2150 3925);
FORCEPROP 1 LAST PACK_TYPE 0402LF
J 0
(-2150 3875);
DISPLAY 0.510638 (-2150 3875);
PAINT SKYBLUE (-2150 3875);
FORCEPROP 1 LAST WATTAGE 1/16W
J 2
(-1800 3875);
DISPLAY 0.510638 (-1800 3875);
PAINT SKYBLUE (-1800 3875);
FORCEPROP 1 LAST MATERIAL CHIP
J 0
(-1850 3825);
DISPLAY 0.510638 (-1850 3825);
PAINT SKYBLUE (-1850 3825);
FORCEPROP 1 LAST TOLERANCE 1%
J 0
(-1775 3875);
DISPLAY 0.510638 (-1775 3875);
PAINT SKYBLUE (-1775 3875);
FORCEPROP 1 LAST VALUE 1K
J 2
(-1700 3975);
DISPLAY 0.510638 (-1700 3975);
PAINT SKYBLUE (-1700 3975);
FORCEPROP 1 LAST PATH I47
J 0
(-1900 4125);
DISPLAY 0.978723 (-1900 4125);
PAINT WHITE (-1900 4125);
DISPLAY INVISIBLE (-1900 4125);
FORCEPROP 2 LAST CDS_LIB pure_quanta
J 0
(-1850 3975);
DISPLAY INVISIBLE (-1850 3975);
FORCEPROP 2 LAST SEC_TYPE 0402LF
J 0
(-1900 4175);
DISPLAY 0.680851 (-1900 4175);
DISPLAY INVISIBLE (-1900 4175);
FORCEPROP 1 LAST LOCATION R210
J 0
(-2025 3975);
DISPLAY 0.702128 (-2025 3975);
PAINT YELLOW (-2025 3975);
FORCEPROP 1 LASTPIN (-1950 3975) $PN 1
J 0
(-1938 3987);
DISPLAY 0.808511 (-1938 3987);
PAINT WHITE (-1938 3987);
FORCEPROP 1 LASTPIN (-1750 3975) $PN 2
J 0
(-1788 3987);
DISPLAY 0.808511 (-1788 3987);
PAINT WHITE (-1788 3987);
FORCEPROP 2 LAST SEC 1
J 0
(-1900 4175);
DISPLAY 0.680851 (-1900 4175);
PAINT MONO (-1900 4175);
DISPLAY INVISIBLE (-1900 4175);
FORCEADD OFFPAGE..2
R 2
(-350 4075);
FORCEPROP 2 LAST $XR0 25 
J 0
(-904 4075);
DISPLAY 0.638298 (-904 4075);
PAINT MONO (-904 4075);
FORCEPROP 1 LAST COMMENT_BODY TRUE
J 2
(-305 3980);
DISPLAY 0.872340 (-305 3980);
PAINT PEACH (-305 3980);
DISPLAY INVISIBLE (-305 3980);
FORCEPROP 1 LAST OFFPAGE TRUE
J 2
(-675 3950);
DISPLAY 0.872340 (-675 3950);
PAINT GREEN (-675 3950);
DISPLAY INVISIBLE (-675 3950);
FORCEPROP 2 LAST PATH I48
J 0
(-300 4150);
DISPLAY 1.021277 (-300 4150);
DISPLAY INVISIBLE (-300 4150);
FORCEPROP 2 LAST CDS_LIB standard
J 0
(-350 4075);
DISPLAY INVISIBLE (-350 4075);
FORCEADD OFFPAGE..1
(-575 4125);
FORCEPROP 2 LAST $XR0 15 
J 0
(-796 4125);
DISPLAY 0.638298 (-796 4125);
PAINT MONO (-796 4125);
FORCEPROP 2 LAST $XR1 22 
J 0
(-886 4125);
DISPLAY 0.638298 (-886 4125);
PAINT MONO (-886 4125);
FORCEPROP 2 LAST $XR2 34 
J 0
(-976 4125);
DISPLAY 0.638298 (-976 4125);
PAINT MONO (-976 4125);
FORCEPROP 2 LAST PATH I49
J 0
(-775 4175);
DISPLAY 1.021277 (-775 4175);
DISPLAY INVISIBLE (-775 4175);
FORCEPROP 1 LAST COMMENT_BODY TRUE
J 0
(-450 4025);
DISPLAY 0.872340 (-450 4025);
PAINT PEACH (-450 4025);
DISPLAY INVISIBLE (-450 4025);
FORCEPROP 1 LAST OFFPAGE TRUE
J 0
(-250 4000);
DISPLAY 0.872340 (-250 4000);
PAINT GREEN (-250 4000);
DISPLAY INVISIBLE (-250 4000);
FORCEPROP 2 LAST CDS_LIB standard
J 0
(-575 4125);
DISPLAY INVISIBLE (-575 4125);
FORCEADD OFFPAGE..3
R 2
(4975 -1150);
FORCEPROP 2 LAST $XR0 10 
J 0
(4696 -1150);
DISPLAY 0.638298 (4696 -1150);
PAINT MONO (4696 -1150);
FORCEPROP 2 LAST $XR1 15 
J 0
(4606 -1150);
DISPLAY 0.638298 (4606 -1150);
PAINT MONO (4606 -1150);
FORCEPROP 2 LAST PATH I5
J 0
(4750 -1100);
DISPLAY 1.021277 (4750 -1100);
DISPLAY INVISIBLE (4750 -1100);
FORCEPROP 1 LAST COMMENT_BODY TRUE
J 2
(5025 -1250);
DISPLAY 0.872340 (5025 -1250);
PAINT PEACH (5025 -1250);
DISPLAY INVISIBLE (5025 -1250);
FORCEPROP 1 LAST OFFPAGE TRUE
J 2
(4650 -1275);
DISPLAY 0.872340 (4650 -1275);
PAINT GREEN (4650 -1275);
DISPLAY INVISIBLE (4650 -1275);
FORCEPROP 2 LAST CDS_LIB standard
J 0
(4975 -1150);
DISPLAY INVISIBLE (4975 -1150);
FORCEADD OFFPAGE..1
(-575 4225);
FORCEPROP 2 LAST $XR1 22 
J 0
(-886 4225);
DISPLAY 0.638298 (-886 4225);
PAINT MONO (-886 4225);
FORCEPROP 2 LAST $XR0 15 
J 0
(-796 4225);
DISPLAY 0.638298 (-796 4225);
PAINT MONO (-796 4225);
FORCEPROP 2 LAST PATH I50
J 0
(-775 4275);
DISPLAY 1.021277 (-775 4275);
DISPLAY INVISIBLE (-775 4275);
FORCEPROP 1 LAST COMMENT_BODY TRUE
J 0
(-450 4125);
DISPLAY 0.872340 (-450 4125);
PAINT PEACH (-450 4125);
DISPLAY INVISIBLE (-450 4125);
FORCEPROP 1 LAST OFFPAGE TRUE
J 0
(-250 4100);
DISPLAY 0.872340 (-250 4100);
PAINT GREEN (-250 4100);
DISPLAY INVISIBLE (-250 4100);
FORCEPROP 2 LAST CDS_LIB standard
J 0
(-575 4225);
DISPLAY INVISIBLE (-575 4225);
FORCEADD Q_RES..2
R 2
(-1025 4350);
FORCEPROP 1 LAST MATERIAL CHIP
J 2
(-1065 4275);
DISPLAY 0.510638 (-1065 4275);
PAINT SKYBLUE (-1065 4275);
FORCEPROP 1 LAST WATTAGE 1/16W
J 2
(-1065 4325);
DISPLAY 0.510638 (-1065 4325);
PAINT SKYBLUE (-1065 4325);
FORCEPROP 1 LAST TOLERANCE 1%
J 2
(-1070 4375);
DISPLAY 0.510638 (-1070 4375);
PAINT SKYBLUE (-1070 4375);
FORCEPROP 1 LAST VALUE 10K
J 2
(-1070 4425);
DISPLAY 0.510638 (-1070 4425);
PAINT SKYBLUE (-1070 4425);
FORCEPROP 1 LAST PART_NUMBER CS31002FB08
J 2
(-1065 4225);
DISPLAY 0.510638 (-1065 4225);
PAINT WHITE (-1065 4225);
FORCEPROP 1 LAST PACK_TYPE 0402LF
J 2
(-1065 4175);
DISPLAY 0.510638 (-1065 4175);
PAINT SKYBLUE (-1065 4175);
FORCEPROP 1 LAST PATH I51
J 2
(-1075 4525);
DISPLAY 0.978723 (-1075 4525);
PAINT WHITE (-1075 4525);
DISPLAY INVISIBLE (-1075 4525);
FORCEPROP 2 LAST CDS_LIB pure_quanta
J 2
(-1025 4350);
DISPLAY INVISIBLE (-1025 4350);
FORCEPROP 1 LAST LOCATION R211
J 2
(-1070 4475);
DISPLAY 0.702128 (-1070 4475);
PAINT YELLOW (-1070 4475);
FORCEPROP 0 LAST $SEC 1
J 2
(-1075 4525);
DISPLAY 0.680851 (-1075 4525);
PAINT MONO (-1075 4525);
DISPLAY INVISIBLE (-1075 4525);
FORCEPROP 0 LAST CDS_SEC 1
J 2
(-1075 4525);
DISPLAY 1.021277 (-1075 4525);
DISPLAY INVISIBLE (-1075 4525);
FORCEPROP 1 LASTPIN (-1025 4450) $PN 1
J 2
(-1030 4412);
DISPLAY 0.808511 (-1030 4412);
PAINT WHITE (-1030 4412);
DISPLAY INVISIBLE (-1030 4412);
FORCEPROP 1 LASTPIN (-1025 4250) $PN 2
J 2
(-1030 4260);
DISPLAY 0.808511 (-1030 4260);
PAINT WHITE (-1030 4260);
DISPLAY INVISIBLE (-1030 4260);
FORCEADD UNIVERSAL_POWER..1
(-1025 4550);
FORCEPROP 3 LASTPIN (-1025 4500) SIG_NAME P3V3_RGM\g
J 0
(-1015 4510);
DISPLAY 0.659574 (-1015 4510);
PAINT MONO (-1015 4510);
DISPLAY INVISIBLE (-1015 4510);
FORCEPROP 1 LAST HDL_POWER P3V3_RGM
J 1
(-1025 4600);
DISPLAY 0.702128 (-1025 4600);
PAINT GREEN (-1025 4600);
FORCEPROP 1 LAST PATH I52
J 0
(-975 4575);
DISPLAY 0.872340 (-975 4575);
PAINT AQUA (-975 4575);
DISPLAY INVISIBLE (-975 4575);
FORCEPROP 2 LAST CDS_LIB logical_power
J 0
(-1025 4550);
DISPLAY INVISIBLE (-1025 4550);
FORCEADD OFFPAGE..1
(-575 4325);
FORCEPROP 2 LAST $XR0 15 
J 0
(-796 4325);
DISPLAY 0.638298 (-796 4325);
PAINT MONO (-796 4325);
FORCEPROP 2 LAST PATH I53
J 0
(-775 4375);
DISPLAY 1.021277 (-775 4375);
DISPLAY INVISIBLE (-775 4375);
FORCEPROP 1 LAST COMMENT_BODY TRUE
J 0
(-450 4225);
DISPLAY 0.872340 (-450 4225);
PAINT PEACH (-450 4225);
DISPLAY INVISIBLE (-450 4225);
FORCEPROP 1 LAST OFFPAGE TRUE
J 0
(-250 4200);
DISPLAY 0.872340 (-250 4200);
PAINT GREEN (-250 4200);
DISPLAY INVISIBLE (-250 4200);
FORCEPROP 2 LAST CDS_LIB standard
J 0
(-575 4325);
DISPLAY INVISIBLE (-575 4325);
FORCEADD OFFPAGE..2
(2650 525);
FORCEPROP 2 LAST $XR0 15 
J 0
(2839 525);
DISPLAY 0.638298 (2839 525);
PAINT MONO (2839 525);
FORCEPROP 2 LAST PATH I61
J 0
(2850 575);
DISPLAY 1.021277 (2850 575);
DISPLAY INVISIBLE (2850 575);
FORCEPROP 1 LAST COMMENT_BODY TRUE
J 0
(2605 430);
DISPLAY 0.872340 (2605 430);
PAINT PEACH (2605 430);
DISPLAY INVISIBLE (2605 430);
FORCEPROP 1 LAST OFFPAGE TRUE
J 0
(2975 400);
DISPLAY 0.872340 (2975 400);
PAINT GREEN (2975 400);
DISPLAY INVISIBLE (2975 400);
FORCEPROP 2 LAST CDS_LIB standard
J 0
(2650 525);
DISPLAY INVISIBLE (2650 525);
FORCEADD UNIVERSAL_POWER..1
(3200 900);
FORCEPROP 3 LASTPIN (3200 850) SIG_NAME P1V8_AUX\g
J 0
(3210 860);
DISPLAY 0.659574 (3210 860);
PAINT MONO (3210 860);
DISPLAY INVISIBLE (3210 860);
FORCEPROP 1 LAST HDL_POWER P1V8_AUX
J 1
(3200 950);
DISPLAY 0.702128 (3200 950);
PAINT GREEN (3200 950);
FORCEPROP 1 LAST PATH I64
J 0
(3250 925);
DISPLAY 0.872340 (3250 925);
PAINT AQUA (3250 925);
DISPLAY INVISIBLE (3250 925);
FORCEPROP 2 LAST CDS_LIB logical_power
J 0
(3200 900);
DISPLAY INVISIBLE (3200 900);
FORCEADD Q_INDUCTOR..1
(3500 850);
FORCEPROP 1 LAST MATERIAL IND
J 0
(3375 905);
DISPLAY 0.510638 (3375 905);
PAINT SKYBLUE (3375 905);
FORCEPROP 2 LAST PACK_TYPE SMLF
J 0
(3375 1050);
DISPLAY 0.510638 (3375 1050);
PAINT SKYBLUE (3375 1050);
FORCEPROP 2 LAST VALUE BLM18PG121SN1D/2000MA
J 0
(3375 1100);
DISPLAY 0.510638 (3375 1100);
PAINT SKYBLUE (3375 1100);
FORCEPROP 1 LAST PART_NUMBER CX8PG121009
J 0
(3375 960);
DISPLAY 0.510638 (3375 960);
PAINT WHITE (3375 960);
FORCEPROP 1 LAST PATH I65
J 0
(3575 905);
DISPLAY 0.723404 (3575 905);
PAINT GREEN (3575 905);
DISPLAY INVISIBLE (3575 905);
FORCEPROP 1 LAST NEEDS_NO_SIZE TRUE
J 0
(3500 850);
DISPLAY 0.468085 (3500 850);
PAINT GREEN (3500 850);
DISPLAY INVISIBLE (3500 850);
FORCEPROP 2 LAST CDS_LIB pure_quanta
J 0
(3500 850);
DISPLAY INVISIBLE (3500 850);
FORCEPROP 1 LAST LOCATION L3
J 0
(3375 1010);
DISPLAY 0.702128 (3375 1010);
PAINT YELLOW (3375 1010);
FORCEPROP 2 LASTPIN (3400 825) $PN 1
J 2
(3390 835);
DISPLAY 0.808511 (3390 835);
PAINT WHITE (3390 835);
FORCEPROP 2 LASTPIN (3600 825) $PN 2
J 0
(3610 835);
DISPLAY 0.808511 (3610 835);
PAINT WHITE (3610 835);
FORCEPROP 2 LAST $SEC 1
J 0
(3375 1150);
DISPLAY 0.680851 (3375 1150);
PAINT MONO (3375 1150);
DISPLAY INVISIBLE (3375 1150);
FORCEPROP 0 LAST CDS_SEC 1
J 0
(3375 1150);
DISPLAY 0.680851 (3375 1150);
PAINT MONO (3375 1150);
DISPLAY INVISIBLE (3375 1150);
FORCEADD UNIVERSAL_GND..1
(3875 375);
FORCEPROP 3 LASTPIN (3875 425) SIG_NAME GND\g
J 0
(3885 435);
DISPLAY 0.659574 (3885 435);
PAINT MONO (3885 435);
DISPLAY INVISIBLE (3885 435);
FORCEPROP 1 LAST PATH I66
J 0
(3950 375);
DISPLAY 0.872340 (3950 375);
PAINT AQUA (3950 375);
DISPLAY INVISIBLE (3950 375);
FORCEPROP 1 LAST HDL_POWER GND
J 1
(3900 300);
DISPLAY 0.702128 (3900 300);
PAINT GREEN (3900 300);
DISPLAY INVISIBLE (3900 300);
FORCEPROP 2 LAST CDS_LIB logical_power
J 0
(3875 375);
DISPLAY INVISIBLE (3875 375);
FORCEADD Q_CAP..1
(4000 650);
FORCEPROP 1 LAST VALUE 0.1UF
J 0
(4050 700);
DISPLAY 0.510638 (4050 700);
PAINT SKYBLUE (4050 700);
FORCEPROP 1 LAST PART_NUMBER CH4104K1B00
J 0
(4050 450);
DISPLAY 0.510638 (4050 450);
PAINT WHITE (4050 450);
FORCEPROP 1 LAST PACK_TYPE 0402
J 0
(4050 500);
DISPLAY 0.510638 (4050 500);
PAINT SKYBLUE (4050 500);
FORCEPROP 1 LAST MATERIAL X7R
J 0
(4050 550);
DISPLAY 0.510638 (4050 550);
PAINT SKYBLUE (4050 550);
FORCEPROP 1 LAST TOLERANCE 10%
J 0
(4050 600);
DISPLAY 0.510638 (4050 600);
PAINT SKYBLUE (4050 600);
FORCEPROP 1 LAST VOLTAGE 25V
J 0
(4050 650);
DISPLAY 0.510638 (4050 650);
PAINT SKYBLUE (4050 650);
FORCEPROP 1 LAST PATH I68
J 0
(4050 800);
DISPLAY 0.978723 (4050 800);
PAINT WHITE (4050 800);
DISPLAY INVISIBLE (4050 800);
FORCEPROP 2 LAST CDS_LIB pure_quanta
J 0
(4000 650);
DISPLAY INVISIBLE (4000 650);
FORCEPROP 1 LAST LOCATION C41
J 0
(4050 750);
DISPLAY 0.702128 (4050 750);
PAINT YELLOW (4050 750);
FORCEPROP 1 LASTPIN (4000 750) $PN 1
J 0
(4010 730);
DISPLAY 0.808511 (4010 730);
PAINT WHITE (4010 730);
FORCEPROP 1 LASTPIN (4000 550) $PN 2
J 0
(4010 530);
DISPLAY 0.808511 (4010 530);
PAINT WHITE (4010 530);
FORCEPROP 2 LAST $SEC 1
J 0
(4050 850);
DISPLAY 0.680851 (4050 850);
PAINT MONO (4050 850);
DISPLAY INVISIBLE (4050 850);
FORCEPROP 0 LAST CDS_SEC 1
J 0
(4050 850);
DISPLAY 0.680851 (4050 850);
PAINT MONO (4050 850);
DISPLAY INVISIBLE (4050 850);
FORCEADD OFFPAGE..3
(4375 825);
FORCEPROP 2 LAST $XR0 15 
J 0
(4589 825);
DISPLAY 0.638298 (4589 825);
PAINT MONO (4589 825);
FORCEPROP 2 LAST PATH I80
J 0
(4600 875);
DISPLAY 1.021277 (4600 875);
DISPLAY INVISIBLE (4600 875);
FORCEPROP 1 LAST COMMENT_BODY TRUE
J 0
(4325 725);
DISPLAY 0.872340 (4325 725);
PAINT PEACH (4325 725);
DISPLAY INVISIBLE (4325 725);
FORCEPROP 1 LAST OFFPAGE TRUE
J 0
(4700 700);
DISPLAY 0.872340 (4700 700);
PAINT GREEN (4700 700);
DISPLAY INVISIBLE (4700 700);
FORCEPROP 2 LAST CDS_LIB standard
J 0
(4375 825);
DISPLAY INVISIBLE (4375 825);
FORCEADD UNIVERSAL_POWER..1
(4700 875);
FORCEPROP 3 LASTPIN (4700 825) SIG_NAME P3V3_AUX\g
J 0
(4710 835);
DISPLAY 0.659574 (4710 835);
PAINT MONO (4710 835);
DISPLAY INVISIBLE (4710 835);
FORCEPROP 1 LAST HDL_POWER P3V3_AUX
J 1
(4700 925);
DISPLAY 0.702128 (4700 925);
PAINT GREEN (4700 925);
FORCEPROP 1 LAST PATH I81
J 0
(4750 900);
DISPLAY 0.872340 (4750 900);
PAINT AQUA (4750 900);
DISPLAY INVISIBLE (4750 900);
FORCEPROP 2 LAST CDS_LIB logical_power
J 0
(4700 875);
DISPLAY INVISIBLE (4700 875);
FORCEADD Q_INDUCTOR..1
(5000 825);
FORCEPROP 1 LAST MATERIAL IND
J 0
(4875 880);
DISPLAY 0.510638 (4875 880);
PAINT SKYBLUE (4875 880);
FORCEPROP 1 LAST PART_NUMBER CX8PG121009
J 0
(4875 935);
DISPLAY 0.510638 (4875 935);
PAINT WHITE (4875 935);
FORCEPROP 2 LAST PACK_TYPE SMLF
J 0
(4875 1025);
DISPLAY 0.510638 (4875 1025);
PAINT SKYBLUE (4875 1025);
FORCEPROP 2 LAST VALUE BLM18PG121SN1D/2000MA
J 0
(4875 1075);
DISPLAY 0.510638 (4875 1075);
PAINT SKYBLUE (4875 1075);
FORCEPROP 1 LAST PATH I82
J 0
(5075 880);
DISPLAY 0.723404 (5075 880);
PAINT GREEN (5075 880);
DISPLAY INVISIBLE (5075 880);
FORCEPROP 1 LAST NEEDS_NO_SIZE TRUE
J 0
(5000 825);
DISPLAY 0.468085 (5000 825);
PAINT GREEN (5000 825);
DISPLAY INVISIBLE (5000 825);
FORCEPROP 2 LAST CDS_LIB pure_quanta
J 0
(5000 825);
DISPLAY INVISIBLE (5000 825);
FORCEPROP 1 LAST LOCATION L4
J 0
(4875 985);
DISPLAY 0.702128 (4875 985);
PAINT YELLOW (4875 985);
FORCEPROP 0 LASTPIN (4900 800) $PN 1
J 2
(4890 810);
DISPLAY 0.808511 (4890 810);
PAINT WHITE (4890 810);
FORCEPROP 0 LASTPIN (5100 800) $PN 2
J 0
(5110 810);
DISPLAY 0.808511 (5110 810);
PAINT WHITE (5110 810);
FORCEPROP 0 LAST $SEC 1
J 0
(4875 1125);
DISPLAY 0.680851 (4875 1125);
PAINT MONO (4875 1125);
DISPLAY INVISIBLE (4875 1125);
FORCEPROP 0 LAST CDS_SEC 1
J 0
(4875 1125);
DISPLAY 0.680851 (4875 1125);
DISPLAY INVISIBLE (4875 1125);
FORCEADD OFFPAGE..2
(4125 1975);
FORCEPROP 2 LAST $XR0 32 
J 0
(4314 1975);
DISPLAY 0.638298 (4314 1975);
PAINT MONO (4314 1975);
FORCEPROP 2 LAST PATH I83
J 0
(4425 2025);
DISPLAY 1.021277 (4425 2025);
DISPLAY INVISIBLE (4425 2025);
FORCEPROP 1 LAST COMMENT_BODY TRUE
J 0
(4080 1880);
DISPLAY 0.872340 (4080 1880);
PAINT PEACH (4080 1880);
DISPLAY INVISIBLE (4080 1880);
FORCEPROP 1 LAST OFFPAGE TRUE
J 0
(4450 1850);
DISPLAY 0.872340 (4450 1850);
PAINT GREEN (4450 1850);
DISPLAY INVISIBLE (4450 1850);
FORCEPROP 2 LAST CDS_LIB standard
J 0
(4125 1975);
DISPLAY INVISIBLE (4125 1975);
FORCEADD OFFPAGE..2
(4125 2025);
FORCEPROP 2 LAST $XR0 32 
J 0
(4314 2025);
DISPLAY 0.638298 (4314 2025);
PAINT MONO (4314 2025);
FORCEPROP 2 LAST PATH I84
J 0
(4425 2075);
DISPLAY 1.021277 (4425 2075);
DISPLAY INVISIBLE (4425 2075);
FORCEPROP 1 LAST COMMENT_BODY TRUE
J 0
(4080 1930);
DISPLAY 0.872340 (4080 1930);
PAINT PEACH (4080 1930);
DISPLAY INVISIBLE (4080 1930);
FORCEPROP 1 LAST OFFPAGE TRUE
J 0
(4450 1900);
DISPLAY 0.872340 (4450 1900);
PAINT GREEN (4450 1900);
DISPLAY INVISIBLE (4450 1900);
FORCEPROP 2 LAST CDS_LIB standard
J 0
(4125 2025);
DISPLAY INVISIBLE (4125 2025);
FORCEADD OFFPAGE..2
(4125 2075);
FORCEPROP 2 LAST $XR0 32 
J 0
(4314 2075);
DISPLAY 0.638298 (4314 2075);
PAINT MONO (4314 2075);
FORCEPROP 2 LAST PATH I85
J 0
(4425 2125);
DISPLAY 1.021277 (4425 2125);
DISPLAY INVISIBLE (4425 2125);
FORCEPROP 1 LAST COMMENT_BODY TRUE
J 0
(4080 1980);
DISPLAY 0.872340 (4080 1980);
PAINT PEACH (4080 1980);
DISPLAY INVISIBLE (4080 1980);
FORCEPROP 1 LAST OFFPAGE TRUE
J 0
(4450 1950);
DISPLAY 0.872340 (4450 1950);
PAINT GREEN (4450 1950);
DISPLAY INVISIBLE (4450 1950);
FORCEPROP 2 LAST CDS_LIB standard
J 0
(4125 2075);
DISPLAY INVISIBLE (4125 2075);
FORCEADD OFFPAGE..2
(4125 2125);
FORCEPROP 2 LAST $XR0 32 
J 0
(4314 2125);
DISPLAY 0.638298 (4314 2125);
PAINT MONO (4314 2125);
FORCEPROP 2 LAST PATH I86
J 0
(4425 2175);
DISPLAY 1.021277 (4425 2175);
DISPLAY INVISIBLE (4425 2175);
FORCEPROP 1 LAST COMMENT_BODY TRUE
J 0
(4080 2030);
DISPLAY 0.872340 (4080 2030);
PAINT PEACH (4080 2030);
DISPLAY INVISIBLE (4080 2030);
FORCEPROP 1 LAST OFFPAGE TRUE
J 0
(4450 2000);
DISPLAY 0.872340 (4450 2000);
PAINT GREEN (4450 2000);
DISPLAY INVISIBLE (4450 2000);
FORCEPROP 2 LAST CDS_LIB standard
J 0
(4125 2125);
DISPLAY INVISIBLE (4125 2125);
FORCEADD UNIVERSAL_GND..1
(5375 350);
FORCEPROP 3 LASTPIN (5375 400) SIG_NAME GND\g
J 0
(5385 410);
DISPLAY 0.659574 (5385 410);
PAINT MONO (5385 410);
DISPLAY INVISIBLE (5385 410);
FORCEPROP 1 LAST PATH I87
J 0
(5450 350);
DISPLAY 0.872340 (5450 350);
PAINT AQUA (5450 350);
DISPLAY INVISIBLE (5450 350);
FORCEPROP 1 LAST HDL_POWER GND
J 1
(5400 275);
DISPLAY 0.702128 (5400 275);
PAINT GREEN (5400 275);
DISPLAY INVISIBLE (5400 275);
FORCEPROP 2 LAST CDS_LIB logical_power
J 0
(5375 350);
DISPLAY INVISIBLE (5375 350);
FORCEADD Q_CAP..1
(5500 625);
FORCEPROP 1 LAST VOLTAGE 25V
J 0
(5550 625);
DISPLAY 0.510638 (5550 625);
PAINT SKYBLUE (5550 625);
FORCEPROP 1 LAST MATERIAL X7R
J 0
(5550 525);
DISPLAY 0.510638 (5550 525);
PAINT SKYBLUE (5550 525);
FORCEPROP 1 LAST TOLERANCE 10%
J 0
(5550 575);
DISPLAY 0.510638 (5550 575);
PAINT SKYBLUE (5550 575);
FORCEPROP 1 LAST PACK_TYPE 0402
J 0
(5550 475);
DISPLAY 0.510638 (5550 475);
PAINT SKYBLUE (5550 475);
FORCEPROP 1 LAST VALUE 0.1UF
J 0
(5550 675);
DISPLAY 0.510638 (5550 675);
PAINT SKYBLUE (5550 675);
FORCEPROP 1 LAST PART_NUMBER CH4104K1B00
J 0
(5550 425);
DISPLAY 0.510638 (5550 425);
PAINT WHITE (5550 425);
FORCEPROP 1 LAST PATH I89
J 0
(5550 775);
DISPLAY 0.978723 (5550 775);
PAINT WHITE (5550 775);
DISPLAY INVISIBLE (5550 775);
FORCEPROP 2 LAST CDS_LIB pure_quanta
J 0
(5500 625);
DISPLAY INVISIBLE (5500 625);
FORCEPROP 1 LAST LOCATION C45
J 0
(5550 725);
DISPLAY 0.702128 (5550 725);
PAINT YELLOW (5550 725);
FORCEPROP 1 LASTPIN (5500 725) $PN 1
J 0
(5510 705);
DISPLAY 0.808511 (5510 705);
PAINT WHITE (5510 705);
FORCEPROP 1 LASTPIN (5500 525) $PN 2
J 0
(5510 505);
DISPLAY 0.808511 (5510 505);
PAINT WHITE (5510 505);
FORCEPROP 0 LAST $SEC 1
J 0
(5550 775);
DISPLAY 0.680851 (5550 775);
PAINT MONO (5550 775);
DISPLAY INVISIBLE (5550 775);
FORCEPROP 0 LAST CDS_SEC 1
J 0
(5550 775);
DISPLAY 0.680851 (5550 775);
DISPLAY INVISIBLE (5550 775);
FORCEADD OFFPAGE..3
(5900 800);
FORCEPROP 2 LAST $XR0 15 
J 0
(6114 800);
DISPLAY 0.638298 (6114 800);
PAINT MONO (6114 800);
FORCEPROP 2 LAST PATH I90
J 0
(6125 850);
DISPLAY 1.021277 (6125 850);
DISPLAY INVISIBLE (6125 850);
FORCEPROP 1 LAST COMMENT_BODY TRUE
J 0
(5850 700);
DISPLAY 0.872340 (5850 700);
PAINT PEACH (5850 700);
DISPLAY INVISIBLE (5850 700);
FORCEPROP 1 LAST OFFPAGE TRUE
J 0
(6225 675);
DISPLAY 0.872340 (6225 675);
PAINT GREEN (6225 675);
DISPLAY INVISIBLE (6225 675);
FORCEPROP 2 LAST CDS_LIB standard
J 0
(5900 800);
DISPLAY INVISIBLE (5900 800);
FORCEADD Q_RES..1
(3300 2825);
FORCEPROP 1 LAST VALUE 0
J 2
(3475 2825);
DISPLAY 0.510638 (3475 2825);
PAINT SKYBLUE (3475 2825);
FORCEPROP 1 LAST MATERIAL CHIP
J 0
(3500 2825);
DISPLAY 0.510638 (3500 2825);
PAINT SKYBLUE (3500 2825);
FORCEPROP 2 LAST CDS_LIB pure_quanta
J 0
(3300 2825);
DISPLAY INVISIBLE (3300 2825);
FORCEPROP 1 LAST PATH I92
J 0
(3250 2975);
DISPLAY 0.978723 (3250 2975);
PAINT WHITE (3250 2975);
DISPLAY INVISIBLE (3250 2975);
FORCEPROP 1 LAST TOLERANCE 5%
J 0
(3300 2725);
DISPLAY 0.510638 (3300 2725);
PAINT SKYBLUE (3300 2725);
DISPLAY INVISIBLE (3300 2725);
FORCEPROP 1 LAST WATTAGE 1/16W
J 2
(3275 2675);
DISPLAY 0.510638 (3275 2675);
PAINT SKYBLUE (3275 2675);
DISPLAY INVISIBLE (3275 2675);
FORCEPROP 1 LAST PACK_TYPE 0402LF
J 0
(3550 2675);
DISPLAY 0.510638 (3550 2675);
PAINT SKYBLUE (3550 2675);
DISPLAY INVISIBLE (3550 2675);
FORCEPROP 1 LAST PART_NUMBER CS00002JB13
J 0
(3250 2925);
DISPLAY 0.510638 (3250 2925);
PAINT WHITE (3250 2925);
DISPLAY INVISIBLE (3250 2925);
FORCEPROP 1 LAST LOCATION R217
J 0
(3100 2825);
DISPLAY 0.702128 (3100 2825);
PAINT YELLOW (3100 2825);
FORCEPROP 1 LASTPIN (3200 2825) $PN 1
J 0
(3212 2837);
DISPLAY 0.808511 (3212 2837);
PAINT WHITE (3212 2837);
FORCEPROP 1 LASTPIN (3400 2825) $PN 2
J 0
(3362 2837);
DISPLAY 0.808511 (3362 2837);
PAINT WHITE (3362 2837);
FORCEPROP 2 LAST $SEC 1
J 0
(3250 3025);
DISPLAY 0.680851 (3250 3025);
PAINT MONO (3250 3025);
DISPLAY INVISIBLE (3250 3025);
FORCEPROP 0 LAST CDS_SEC 1
J 0
(3250 3025);
DISPLAY 0.680851 (3250 3025);
PAINT MONO (3250 3025);
DISPLAY INVISIBLE (3250 3025);
FORCEADD Q_RES..1
(3300 2775);
FORCEPROP 1 LAST VALUE 0
J 2
(3475 2775);
DISPLAY 0.510638 (3475 2775);
PAINT SKYBLUE (3475 2775);
FORCEPROP 1 LAST MATERIAL CHIP
J 0
(3500 2775);
DISPLAY 0.510638 (3500 2775);
PAINT SKYBLUE (3500 2775);
FORCEPROP 2 LAST CDS_LIB pure_quanta
J 0
(3300 2775);
DISPLAY INVISIBLE (3300 2775);
FORCEPROP 1 LAST PATH I93
J 0
(3250 2925);
DISPLAY 0.978723 (3250 2925);
PAINT WHITE (3250 2925);
DISPLAY INVISIBLE (3250 2925);
FORCEPROP 1 LAST TOLERANCE 5%
J 0
(3300 2675);
DISPLAY 0.510638 (3300 2675);
PAINT SKYBLUE (3300 2675);
DISPLAY INVISIBLE (3300 2675);
FORCEPROP 1 LAST WATTAGE 1/16W
J 2
(3275 2625);
DISPLAY 0.510638 (3275 2625);
PAINT SKYBLUE (3275 2625);
DISPLAY INVISIBLE (3275 2625);
FORCEPROP 1 LAST PACK_TYPE 0402LF
J 0
(3550 2625);
DISPLAY 0.510638 (3550 2625);
PAINT SKYBLUE (3550 2625);
DISPLAY INVISIBLE (3550 2625);
FORCEPROP 1 LAST PART_NUMBER CS00002JB13
J 0
(3250 2875);
DISPLAY 0.510638 (3250 2875);
PAINT WHITE (3250 2875);
DISPLAY INVISIBLE (3250 2875);
FORCEPROP 1 LAST LOCATION R218
J 0
(3100 2775);
DISPLAY 0.702128 (3100 2775);
PAINT YELLOW (3100 2775);
FORCEPROP 1 LASTPIN (3200 2775) $PN 1
J 0
(3212 2787);
DISPLAY 0.808511 (3212 2787);
PAINT WHITE (3212 2787);
FORCEPROP 1 LASTPIN (3400 2775) $PN 2
J 0
(3362 2787);
DISPLAY 0.808511 (3362 2787);
PAINT WHITE (3362 2787);
FORCEPROP 2 LAST $SEC 1
J 0
(3250 2975);
DISPLAY 0.680851 (3250 2975);
PAINT MONO (3250 2975);
DISPLAY INVISIBLE (3250 2975);
FORCEPROP 0 LAST CDS_SEC 1
J 0
(3250 2975);
DISPLAY 0.680851 (3250 2975);
PAINT MONO (3250 2975);
DISPLAY INVISIBLE (3250 2975);
FORCEADD OFFPAGE..4
(3150 2925);
FORCEPROP 2 LAST $XR0 15 
J 0
(3336 2925);
DISPLAY 0.638298 (3336 2925);
PAINT MONO (3336 2925);
FORCEPROP 2 LAST PATH I94
J 0
(3350 2975);
DISPLAY 1.021277 (3350 2975);
DISPLAY INVISIBLE (3350 2975);
FORCEPROP 1 LAST COMMENT_BODY TRUE
J 0
(3125 2825);
DISPLAY 0.872340 (3125 2825);
PAINT PEACH (3125 2825);
DISPLAY INVISIBLE (3125 2825);
FORCEPROP 1 LAST OFFPAGE TRUE
J 0
(3475 2800);
DISPLAY 0.872340 (3475 2800);
PAINT GREEN (3475 2800);
DISPLAY INVISIBLE (3475 2800);
FORCEPROP 2 LAST CDS_LIB standard
J 0
(3150 2925);
DISPLAY INVISIBLE (3150 2925);
FORCEADD OFFPAGE..4
(3150 2975);
FORCEPROP 2 LAST $XR0 15 
J 0
(3336 2975);
DISPLAY 0.638298 (3336 2975);
PAINT MONO (3336 2975);
FORCEPROP 2 LAST PATH I95
J 0
(3350 3025);
DISPLAY 1.021277 (3350 3025);
DISPLAY INVISIBLE (3350 3025);
FORCEPROP 1 LAST COMMENT_BODY TRUE
J 0
(3125 2875);
DISPLAY 0.872340 (3125 2875);
PAINT PEACH (3125 2875);
DISPLAY INVISIBLE (3125 2875);
FORCEPROP 1 LAST OFFPAGE TRUE
J 0
(3475 2850);
DISPLAY 0.872340 (3475 2850);
PAINT GREEN (3475 2850);
DISPLAY INVISIBLE (3475 2850);
FORCEPROP 2 LAST CDS_LIB standard
J 0
(3150 2975);
DISPLAY INVISIBLE (3150 2975);
FORCEADD OFFPAGE..2
(3150 3125);
FORCEPROP 2 LAST $XR0 13 
J 0
(3339 3125);
DISPLAY 0.638298 (3339 3125);
PAINT MONO (3339 3125);
FORCEPROP 2 LAST PATH I96
J 0
(3350 3175);
DISPLAY 1.021277 (3350 3175);
DISPLAY INVISIBLE (3350 3175);
FORCEPROP 1 LAST COMMENT_BODY TRUE
J 0
(3105 3030);
DISPLAY 0.872340 (3105 3030);
PAINT PEACH (3105 3030);
DISPLAY INVISIBLE (3105 3030);
FORCEPROP 1 LAST OFFPAGE TRUE
J 0
(3475 3000);
DISPLAY 0.872340 (3475 3000);
PAINT GREEN (3475 3000);
DISPLAY INVISIBLE (3475 3000);
FORCEPROP 2 LAST CDS_LIB standard
J 0
(3150 3125);
DISPLAY INVISIBLE (3150 3125);
FORCEADD QUANTA_TITLE_BLOCK_C..1
(6275 -1875);
FORCEPROP 0 LAST CDS_CON_LAST_MODIFIED Fri Aug 25 17:25:37 2023
J 0
(4390 -1860);
DISPLAY INVISIBLE (4390 -1860);
FORCEPROP 2 LAST Q_DEPT 
J 1
(2512 -1826);
DISPLAY 1.957447 (2512 -1826);
PAINT GREEN (2512 -1826);
FORCEPROP 1 LAST CUSTOM_TXT_CDS <CON_LAST_MODIFIED>
J 0
(4390 -1860);
DISPLAY 0.978723 (4390 -1860);
FORCEPROP 2 LAST CUSTOM_TXT_CDS <XR_PAGE_TITLE>
J 0
(-1615 3375);
DISPLAY 0.638298 (-1615 3375);
PAINT PINK (-1615 3375);
DISPLAY INVISIBLE (-1615 3375);
FORCEPROP 1 LAST CUSTOM_TXT_CDS <NAME_2>
J 0
(3100 -1825);
FORCEPROP 1 LAST CUSTOM_TXT_CDS <NAME_1>
J 0
(3100 -1700);
FORCEPROP 1 LAST CUSTOM_TXT_CDS <Q_NUMBER>
J 0
(4872 -1772);
DISPLAY 1.212766 (4872 -1772);
FORCEPROP 1 LAST CUSTOM_TXT_CDS <Q_PROJ>
J 0
(3893 -1773);
DISPLAY 1.212766 (3893 -1773);
FORCEPROP 1 LAST CUSTOM_TXT_CDS <Q_REV>
J 0
(6091 -1772);
DISPLAY 1.212766 (6091 -1772);
FORCEPROP 1 LAST CUSTOM_TXT_CDS <CON_PAGE_NUM> OF <CON_TOTAL_PAGES>
J 0
(5829 -1857);
DISPLAY 0.978723 (5829 -1857);
FORCEPROP 1 LAST Q_TITLE BMC 4
J 0
(-3091 -1849);
DISPLAY 2.446809 (-3091 -1849);
PAINT GREEN (-3091 -1849);
FORCEPROP 1 LAST COMMENT_BODY TRUE
J 0
(6287 -1888);
DISPLAY 0.978723 (6287 -1888);
PAINT PEACH (6287 -1888);
DISPLAY INVISIBLE (6287 -1888);
FORCEPROP 2 LAST PAGE_BORDER TRUE
J 0
(-1615 3375);
DISPLAY 0.638298 (-1615 3375);
PAINT PINK (-1615 3375);
DISPLAY INVISIBLE (-1615 3375);
FORCEPROP 1 LAST CDS_LMAN_SYM_OUTLINE -9475,6775,100,-125
J 0
(6275 -1875);
DISPLAY 0.468085 (6275 -1875);
PAINT GREEN (6275 -1875);
DISPLAY INVISIBLE (6275 -1875);
FORCEPROP 2 LAST CDS_LIB pure_quanta
J 0
(6275 -1875);
DISPLAY INVISIBLE (6275 -1875);
FORCEPROP 2 LAST CDS_XR_PAGE_TITLE CR-15 : @SCM_LIB.SCM(SCH_1):PAGE15
J 0
(-1615 3375);
DISPLAY 0.638298 (-1615 3375);
PAINT PINK (-1615 3375);
DISPLAY INVISIBLE (-1615 3375);
FORCEADD DNS..2
(5725 -1150);
PAINT RED (5725 -1150);
FORCEPROP 1 LAST COMMENT_BODY TRUE
R 1
J 0
(5800 -1375);
DISPLAY 0.872340 (5800 -1375);
PAINT PEACH (5800 -1375);
DISPLAY INVISIBLE (5800 -1375);
FORCEPROP 2 LAST CDS_LIB mstr_misc
J 0
(5725 -1150);
DISPLAY INVISIBLE (5725 -1150);
FORCEADD DNS..1
(3875 3025);
PAINT RED (3875 3025);
FORCEPROP 1 LAST COMMENT_BODY TRUE
R 1
J 0
(3950 2800);
DISPLAY 0.872340 (3950 2800);
PAINT PEACH (3950 2800);
DISPLAY INVISIBLE (3950 2800);
FORCEPROP 2 LAST CDS_LIB mstr_misc
J 0
(3875 3025);
DISPLAY INVISIBLE (3875 3025);
FORCEADD DNS..1
(2425 -825);
PAINT RED (2425 -825);
FORCEPROP 1 LAST COMMENT_BODY TRUE
R 1
J 0
(2500 -1050);
DISPLAY 0.872340 (2500 -1050);
PAINT PEACH (2500 -1050);
DISPLAY INVISIBLE (2500 -1050);
FORCEPROP 2 LAST CDS_LIB mstr_misc
J 0
(2425 -825);
DISPLAY INVISIBLE (2425 -825);
FORCEADD DESIGN_NOTE..1
(-2275 1675);
FORCEPROP 0 LAST L2 ADC 2
J 0
(-2450 1525);
DISPLAY 1.021277 (-2450 1525);
PAINT WHITE (-2450 1525);
FORCEPROP 0 LAST L1 SCALED TO 1.35V
J 0
(-2450 1425);
DISPLAY 1.021277 (-2450 1425);
PAINT WHITE (-2450 1425);
FORCEPROP 1 LAST COMMENT_BODY TRUE
J 0
(-2250 1775);
DISPLAY 0.978723 (-2250 1775);
PAINT PEACH (-2250 1775);
DISPLAY INVISIBLE (-2250 1775);
FORCEPROP 2 LAST CDS_LIB logical_power
J 0
(-2275 1675);
DISPLAY INVISIBLE (-2275 1675);
FORCEADD DESIGN_NOTE..1
(-1275 1650);
FORCEPROP 0 LAST L2 ADC 6
J 0
(-1450 1500);
DISPLAY 1.021277 (-1450 1500);
PAINT WHITE (-1450 1500);
FORCEPROP 1 LAST COMMENT_BODY TRUE
J 0
(-1250 1750);
DISPLAY 0.978723 (-1250 1750);
PAINT PEACH (-1250 1750);
DISPLAY INVISIBLE (-1250 1750);
FORCEPROP 2 LAST CDS_LIB logical_power
J 0
(-1275 1650);
DISPLAY INVISIBLE (-1275 1650);
FORCEADD DESIGN_NOTE..1
(-2275 550);
FORCEPROP 0 LAST L2 ADC 3
J 0
(-2450 400);
DISPLAY 1.021277 (-2450 400);
PAINT WHITE (-2450 400);
FORCEPROP 0 LAST L1 SCALED TO 1.35V
J 0
(-2450 300);
DISPLAY 1.021277 (-2450 300);
PAINT WHITE (-2450 300);
FORCEPROP 1 LAST COMMENT_BODY TRUE
J 0
(-2250 650);
DISPLAY 0.978723 (-2250 650);
PAINT PEACH (-2250 650);
DISPLAY INVISIBLE (-2250 650);
FORCEPROP 2 LAST CDS_LIB logical_power
J 0
(-2275 550);
DISPLAY INVISIBLE (-2275 550);
FORCEADD DESIGN_NOTE..1
(-1175 475);
FORCEPROP 0 LAST L2 ADC 10
J 0
(-1350 325);
DISPLAY 1.021277 (-1350 325);
PAINT WHITE (-1350 325);
FORCEPROP 1 LAST COMMENT_BODY TRUE
J 0
(-1150 575);
DISPLAY 0.978723 (-1150 575);
PAINT PEACH (-1150 575);
DISPLAY INVISIBLE (-1150 575);
FORCEPROP 2 LAST CDS_LIB logical_power
J 0
(-1175 475);
DISPLAY INVISIBLE (-1175 475);
FORCEADD DESIGN_NOTE..1
(-1050 -1000);
FORCEPROP 0 LAST L2 ADC 5
J 0
(-1225 -1150);
DISPLAY 1.021277 (-1225 -1150);
PAINT WHITE (-1225 -1150);
FORCEPROP 0 LAST L1 3.3V SCALED TO 1.35V
J 0
(-1225 -1225);
DISPLAY 1.021277 (-1225 -1225);
PAINT WHITE (-1225 -1225);
FORCEPROP 1 LAST COMMENT_BODY TRUE
J 0
(-1025 -900);
DISPLAY 0.978723 (-1025 -900);
PAINT PEACH (-1025 -900);
DISPLAY INVISIBLE (-1025 -900);
FORCEPROP 0 LASTPROP L3 1.8V SCALED TO 0.74V
J 0
(-1225 -1300);
DISPLAY 1.021277 (-1225 -1300);
PAINT WHITE (-1225 -1300);
FORCEPROP 2 LAST CDS_LIB logical_power
J 0
(-1050 -1000);
DISPLAY INVISIBLE (-1050 -1000);
FORCEADD DESIGN_NOTE..1
(-2175 -525);
FORCEPROP 0 LAST L1 SCALED TO 1.35V
J 0
(-2350 -775);
DISPLAY 1.021277 (-2350 -775);
PAINT WHITE (-2350 -775);
FORCEPROP 0 LAST L2 ADC 4
J 0
(-2350 -675);
DISPLAY 1.021277 (-2350 -675);
PAINT WHITE (-2350 -675);
FORCEPROP 1 LAST COMMENT_BODY TRUE
J 0
(-2150 -425);
DISPLAY 0.978723 (-2150 -425);
PAINT PEACH (-2150 -425);
DISPLAY INVISIBLE (-2150 -425);
FORCEPROP 2 LAST CDS_LIB logical_power
J 0
(-2175 -525);
DISPLAY INVISIBLE (-2175 -525);
FORCEADD DESIGN_NOTE..1
(-850 -200);
FORCEPROP 0 LAST L1 VBAT 1/3 SCALED
J 0
(-1025 -450);
DISPLAY 1.021277 (-1025 -450);
PAINT WHITE (-1025 -450);
FORCEPROP 0 LAST L2 ADC 7
J 0
(-1025 -350);
DISPLAY 1.021277 (-1025 -350);
PAINT WHITE (-1025 -350);
FORCEPROP 1 LAST COMMENT_BODY TRUE
J 0
(-825 -100);
DISPLAY 0.978723 (-825 -100);
PAINT PEACH (-825 -100);
DISPLAY INVISIBLE (-825 -100);
FORCEPROP 2 LAST CDS_LIB logical_power
J 0
(-850 -200);
DISPLAY INVISIBLE (-850 -200);
FORCEADD DNS..1
(4700 -625);
PAINT RED (4700 -625);
FORCEPROP 1 LAST COMMENT_BODY TRUE
R 1
J 0
(4775 -850);
DISPLAY 0.872340 (4775 -850);
PAINT PEACH (4775 -850);
DISPLAY INVISIBLE (4775 -850);
FORCEPROP 2 LAST CDS_LIB mstr_misc
J 0
(4700 -625);
DISPLAY INVISIBLE (4700 -625);
FORCEADD DESIGN_NOTE..1
(-1875 2175);
FORCEPROP 0 LAST L2 ADC 1
J 0
(-2050 2025);
DISPLAY 1.021277 (-2050 2025);
PAINT WHITE (-2050 2025);
FORCEPROP 0 LAST L1 SCALED TO 1.35V
J 0
(-2050 1925);
DISPLAY 1.021277 (-2050 1925);
PAINT WHITE (-2050 1925);
FORCEPROP 1 LAST COMMENT_BODY TRUE
J 0
(-1850 2275);
DISPLAY 0.978723 (-1850 2275);
PAINT PEACH (-1850 2275);
DISPLAY INVISIBLE (-1850 2275);
FORCEPROP 2 LAST CDS_LIB logical_power
J 0
(-1875 2175);
DISPLAY INVISIBLE (-1875 2175);
FORCEADD DESIGN_NOTE..1
(-1875 3125);
FORCEPROP 0 LAST L2 ADC 0
J 0
(-2050 2975);
DISPLAY 1.021277 (-2050 2975);
PAINT WHITE (-2050 2975);
FORCEPROP 0 LAST L1 SCALED TO 1.35V
J 0
(-2050 2875);
DISPLAY 1.021277 (-2050 2875);
PAINT WHITE (-2050 2875);
FORCEPROP 1 LAST COMMENT_BODY TRUE
J 0
(-1850 3225);
DISPLAY 0.978723 (-1850 3225);
PAINT PEACH (-1850 3225);
DISPLAY INVISIBLE (-1850 3225);
FORCEPROP 2 LAST CDS_LIB logical_power
J 0
(-1875 3125);
DISPLAY INVISIBLE (-1875 3125);
FORCEADD DNS..1
(-2650 4300);
PAINT RED (-2650 4300);
FORCEPROP 1 LAST COMMENT_BODY TRUE
R 1
J 0
(-2575 4075);
DISPLAY 0.872340 (-2575 4075);
PAINT PEACH (-2575 4075);
DISPLAY INVISIBLE (-2575 4075);
FORCEPROP 2 LAST CDS_LIB mstr_misc
J 0
(-2650 4300);
DISPLAY INVISIBLE (-2650 4300);
FORCEADD DNS..1
(-2875 4250);
PAINT RED (-2875 4250);
FORCEPROP 1 LAST COMMENT_BODY TRUE
R 1
J 0
(-2800 4025);
DISPLAY 0.872340 (-2800 4025);
PAINT PEACH (-2800 4025);
DISPLAY INVISIBLE (-2800 4025);
FORCEPROP 2 LAST CDS_LIB mstr_misc
J 0
(-2875 4250);
DISPLAY INVISIBLE (-2875 4250);
WIRE 16 -1 (-500 725)(-500 900);
WIRE 16 -1 (3200 850)(3200 825);
WIRE 16 -1 (3625 -550)(3625 -350);
WIRE 16 -1 (3625 -550)(3375 -550);
WIRE 16 -1 (1850 -750)(1850 -850);
WIRE 16 -1 (4225 4075)(4225 4000);
WIRE 16 -1 (4700 825)(4700 800);
WIRE 16 -1 (5900 -350)(5900 -150);
WIRE 16 -1 (5900 -350)(5650 -350);
WIRE 16 -1 (4325 -350)(4325 -150);
WIRE 16 -1 (4600 -350)(4325 -350);
WIRE 16 -1 (4125 -550)(4125 -650);
WIRE 16 -1 (2050 -550)(2050 -350);
WIRE 16 -1 (2325 -550)(2050 -550);
WIRE 16 -1 (-1025 4500)(-1025 4450);
WIRE 16 -1 (-2900 4450)(-2900 4425);
WIRE 16 -1 (-175 1100)(-175 1000);
WIRE 16 -1 (-1650 1525)(-1650 1575);
WIRE 16 -1 (-1625 425)(-1625 475);
WIRE 16 -1 (-2625 3575)(-2625 3625);
WIRE 16 -1 (-2625 2625)(-2625 2675);
WIRE 16 -1 (-2625 1625)(-2625 1675);
WIRE 16 -1 (-2625 500)(-2625 550);
WIRE 16 -1 (-1500 -1075)(-1500 -1025);
WIRE 16 -1 (-2625 -600)(-2625 -550);
WIRE 16 -1 (5175 2225)(5175 2175);
WIRE 16 -1 (5175 1375)(5175 1325);
WIRE 16 -1 (5575 1900)(5575 1925);
WIRE 16 -1 (-2250 3975)(-2250 3875);
WIRE 16 -1 (-1950 3975)(-2250 3975);
WIRE 16 -1 (4625 2200)(4625 2150);
WIRE 16 -1 (4450 2200)(4625 2200);
WIRE 16 -1 (4625 2200)(4675 2200);
WIRE 16 -1 (4200 2975)(4200 2950);
WIRE 16 -1 (4200 3050)(4200 2975);
WIRE 16 -1 (4000 2975)(4200 2975);
WIRE 16 -1 (-2625 2875)(-2625 2925);
WIRE 16 -1 (3250 -950)(3250 -900);
WIRE 16 -1 (5950 -1150)(5950 -1350);
WIRE 16 -1 (5800 -1150)(5950 -1150);
WIRE 16 -1 (650 -1450)(650 -1500);
WIRE 16 -1 (650 -1450)(1100 -1450);
WIRE 16 -1 (650 -1350)(650 -1450);
WIRE 16 -1 (250 -1200)(250 -1275);
WIRE 16 -1 (-2625 1925)(-2625 1975);
WIRE 16 -1 (-2625 925)(-2625 975);
WIRE 16 -1 (-175 700)(-175 550);
WIRE 16 -1 (-2625 -200)(-2625 -150);
WIRE 16 -1 (-2625 -1300)(-2625 -1250);
WIRE 16 -1 (-1650 800)(-1650 925);
WIRE 16 -1 (-1625 -300)(-1625 -175);
WIRE 16 -1 (-1500 -1775)(-1500 -1725);
WIRE 16 -1 (5525 -750)(5525 -700);
WIRE 16 -1 (1075 375)(1075 225);
WIRE 16 -1 (900 375)(1075 375);
WIRE 16 -1 (3875 425)(3875 475);
WIRE 16 -1 (5375 400)(5375 450);
WIRE 16 -1 (6100 4075)(6100 4175);
WIRE 16 -1 (2325 -850)(1850 -850);
WIRE 16 -1 (4675 2275)(4675 2200);
WIRE 16 -1 (4450 2275)(4450 2200);
WIRE 16 -1 (5700 4175)(6100 4175);
WIRE 16 -1 (6100 4175)(6100 4275);
WIRE 16 -1 (5700 4275)(6100 4275);
WIRE 16 -1 (6100 4375)(6100 4275);
WIRE 16 -1 (5700 4375)(6100 4375);
WIRE 16 -1 (3375 -825)(3375 -900);
WIRE 16 -1 (3250 -900)(3375 -900);
WIRE 16 -1 (3175 -900)(3250 -900);
WIRE 16 -1 (3175 -825)(3175 -900);
WIRE 16 -1 (-2900 4375)(-2900 4425);
WIRE 16 -1 (-2900 4425)(-2650 4425);
WIRE 16 -1 (-2650 4425)(-2650 4375);
WIRE 16 -1 (4225 4000)(4325 4000);
WIRE 16 -1 (4225 4000)(4225 3900);
WIRE 16 -1 (4325 3900)(4225 3900);
WIRE 16 -1 (3375 -625)(3375 -550);
WIRE 16 -1 (3175 -625)(3175 -550);
WIRE 16 -1 (3375 -550)(3175 -550);
WIRE 16 -1 (3000 -550)(2525 -550);
WIRE 16 -1 (3175 -550)(3000 -550);
WIRE 16 -1 (3000 -850)(3000 -550);
WIRE 16 -1 (2525 -850)(3000 -850);
WIRE 16 -1 (1100 -1350)(1100 -1450);
WIRE 16 -1 (-2625 3000)(-2625 2925);
WIRE 16 -1 (-2625 2925)(-2425 2925);
WIRE 16 -1 (-2425 2925)(-2425 3000);
WIRE 16 -1 (-2625 2050)(-2625 1975);
WIRE 16 -1 (-2625 1975)(-2425 1975);
WIRE 16 -1 (-2425 1975)(-2425 2050);
WIRE 16 -1 (-2625 1050)(-2625 975);
WIRE 16 -1 (-2625 975)(-2425 975);
WIRE 16 -1 (-2425 975)(-2425 1050);
WIRE 16 -1 (-2625 -75)(-2625 -150);
WIRE 16 -1 (-2625 -150)(-2425 -150);
WIRE 16 -1 (-2425 -150)(-2425 -75);
WIRE 16 -1 (-2625 -1175)(-2625 -1250);
WIRE 16 -1 (-2625 -1250)(-2425 -1250);
WIRE 16 -1 (-2425 -1250)(-2425 -1175);
WIRE 16 -1 (-175 900)(-175 1000);
WIRE 16 -1 (75 1000)(-175 1000);
WIRE 16 -1 (75 525)(75 1000);
WIRE 16 -1 (250 525)(75 525);
WIRE 16 -1 (-1500 -1650)(-1500 -1725);
WIRE 16 -1 (-1500 -1725)(-1300 -1725);
WIRE 16 -1 (-1300 -1725)(-1300 -1650);
WIRE 16 -1 (4600 -650)(4125 -650);
WIRE 16 -1 (5450 -625)(5450 -700);
WIRE 16 -1 (5450 -700)(5525 -700);
WIRE 16 -1 (5525 -700)(5650 -700);
WIRE 16 -1 (5650 -625)(5650 -700);
WIRE 16 -1 (4000 3050)(4200 3050);
WIRE 16 -1 (5650 -425)(5650 -350);
WIRE 16 -1 (5450 -425)(5450 -350);
WIRE 16 -1 (5650 -350)(5450 -350);
WIRE 16 -1 (5275 -350)(4800 -350);
WIRE 16 -1 (5450 -350)(5275 -350);
WIRE 16 -1 (5275 -650)(5275 -350);
WIRE 16 -1 (4800 -650)(5275 -650);
WIRE 16 -1 (5175 2175)(5175 1875);
WIRE 16 -1 (5575 2125)(5575 2175);
WIRE 16 -1 (5575 2175)(5175 2175);
WIRE 16 -1 (3200 825)(3400 825);
WIRE 16 -1 (4000 550)(4000 475);
WIRE 16 -1 (3875 475)(4000 475);
WIRE 16 -1 (3800 475)(3875 475);
WIRE 16 -1 (3800 550)(3800 475);
WIRE 16 -1 (4700 800)(4900 800);
WIRE 16 -1 (5500 525)(5500 450);
WIRE 16 -1 (5375 450)(5500 450);
WIRE 16 -1 (5300 450)(5375 450);
WIRE 16 -1 (5300 525)(5300 450);
WIRE 16 -1 (650 -975)(650 -1150);
WIRE 16 -1 (650 -850)(650 -975);
WIRE 16 -1 (650 -975)(1100 -975);
FORCEPROP 2 LAST SIG_NAME P3V_BAT_SENSOR
J 0
(715 -965);
DISPLAY 0.808511 (715 -965);
WIRE 16 -1 (1100 -975)(1100 -1150);
WIRE 16 -1 (1100 -975)(1225 -975);
WIRE 16 3135 (-675 100)(2975 100);
WIRE 16 3135 (2975 1300)(2975 100);
WIRE 16 3135 (-675 100)(-675 1300);
WIRE 16 3135 (-675 1300)(2975 1300);
WIRE 16 -1 (-1300 -1400)(-1300 -1450);
WIRE 16 -1 (-650 -1400)(-1300 -1400);
WIRE 16 -1 (-1500 -1400)(-1500 -1450);
WIRE 16 -1 (-1300 -1400)(-1500 -1400);
FORCEPROP 2 LAST SIG_NAME PGPPA_BMC_AUX_SENSOR
J 0
(-1435 -1390);
DISPLAY 0.808511 (-1435 -1390);
WIRE 16 -1 (-1500 -1275)(-1500 -1400);
WIRE 16 -1 (250 -750)(250 -1000);
WIRE 16 -1 (450 -750)(250 -750);
FORCEPROP 2 LAST SIG_NAME BATTERY_DETECT_R
J 0
(-285 -740);
DISPLAY 0.808511 (-285 -740);
WIRE 16 -1 (-300 -750)(250 -750);
WIRE 16 3135 (3025 300)(6200 300);
WIRE 16 3135 (3025 300)(3025 1225);
WIRE 16 3135 (6200 1225)(6200 300);
WIRE 16 3135 (6250 1225)(6200 1225);
WIRE 16 3135 (3725 1225)(3025 1225);
WIRE 16 3135 (6200 1225)(3725 1225);
WIRE 16 3135 (3725 1225)(3725 1850);
WIRE 16 3135 (6250 1225)(6250 2450);
WIRE 16 3135 (6250 2450)(5025 2450);
WIRE 16 3135 (5025 1850)(3725 1850);
WIRE 16 3135 (5025 1850)(5025 2450);
WIRE 16 -1 (900 525)(1650 525);
FORCEPROP 2 LAST SIG_NAME BMC_CLK_25M_R
J 0
(990 535);
DISPLAY 0.808511 (990 535);
WIRE 16 -1 (4925 1575)(4125 1575);
FORCEPROP 2 LAST SIG_NAME PWR_BTN_BMC_N
J 0
(4140 1585);
DISPLAY 0.808511 (4140 1585);
WIRE 16 -1 (250 375)(-500 375);
FORCEPROP 2 LAST SIG_NAME PU_25M_BMC_CLK_EN
J 0
(-460 385);
DISPLAY 0.808511 (-460 385);
WIRE 16 -1 (-500 525)(-500 375);
WIRE 16 3135 (1675 -1075)(3925 -1075);
WIRE 16 3135 (1675 -1075)(1675 50);
WIRE 16 3135 (3925 50)(3925 -1075);
WIRE 16 3135 (3925 50)(1675 50);
WIRE 16 3135 (3950 -875)(6200 -875);
WIRE 16 3135 (3950 -875)(3950 250);
WIRE 16 3135 (6200 250)(6200 -875);
WIRE 16 3135 (6200 250)(3950 250);
WIRE 16 -1 (-2625 2300)(-2625 2250);
WIRE 16 -1 (-2625 2425)(-2625 2300);
WIRE 16 -1 (-2425 2300)(-2425 2250);
WIRE 16 -1 (-2125 2300)(-2425 2300);
WIRE 16 -1 (-2425 2300)(-2625 2300);
FORCEPROP 2 LAST SIG_NAME P5V_SENSOR
J 0
(-2560 2310);
DISPLAY 0.808511 (-2560 2310);
WIRE 16 -1 (-2625 3250)(-2625 3200);
WIRE 16 -1 (-2625 3375)(-2625 3250);
WIRE 16 -1 (-2425 3250)(-2425 3200);
WIRE 16 -1 (-2125 3250)(-2425 3250);
WIRE 16 -1 (-2425 3250)(-2625 3250);
FORCEPROP 2 LAST SIG_NAME P12V_SENSOR
J 0
(-2560 3260);
DISPLAY 0.808511 (-2560 3260);
WIRE 16 -1 (-1625 225)(-1625 75);
WIRE 16 -1 (-1625 75)(-1625 25);
WIRE 16 -1 (-1125 75)(-1625 75);
FORCEPROP 2 LAST SIG_NAME P1V0_SENSOR
J 0
(-1560 85);
DISPLAY 0.808511 (-1560 85);
WIRE 16 -1 (-1650 1175)(-1650 1125);
WIRE 16 -1 (-1650 1325)(-1650 1175);
WIRE 16 -1 (-1150 1175)(-1650 1175);
FORCEPROP 2 LAST SIG_NAME P1V2_SENSOR
J 0
(-1585 1185);
DISPLAY 0.808511 (-1585 1185);
WIRE 16 -1 (-200 1975)(450 1975);
FORCEPROP 2 LAST SIG_NAME JTAG_1_BMC_TDO
J 0
(-210 1985);
DISPLAY 0.851064 (-210 1985);
WIRE 16 -1 (-625 2825)(450 2825);
FORCEPROP 2 LAST SIG_NAME P1V8_SENSOR
J 0
(-560 2835);
DISPLAY 0.808511 (-560 2835);
WIRE 16 -1 (450 1725)(-525 1725);
FORCEPROP 2 LAST SIG_NAME JTAG_SCM_TMS
J 0
(-460 1735);
DISPLAY 0.808511 (-460 1735);
WIRE 16 -1 (-525 4325)(450 4325);
FORCEPROP 2 LAST SIG_NAME BMC_CLK_25M
J 0
(-475 4335);
DISPLAY 0.808511 (-475 4335);
WIRE 16 -1 (-525 4125)(450 4125);
FORCEPROP 2 LAST SIG_NAME RST_EXTRST_N
J 0
(-475 4135);
DISPLAY 0.808511 (-475 4135);
WIRE 16 -1 (-525 4225)(450 4225);
FORCEPROP 2 LAST SIG_NAME RST_BMC_SRST_N
J 0
(-475 4235);
DISPLAY 0.808511 (-475 4235);
WIRE 16 -1 (650 -275)(650 -550);
FORCEPROP 2 LAST SIG_NAME P3V_BAT_R1
J 0
(265 -390);
DISPLAY 0.808511 (265 -390);
WIRE 16 -1 (3100 2975)(2250 2975);
FORCEPROP 2 LAST SIG_NAME P3V3_BMC_USB2AV33
J 0
(2390 2985);
DISPLAY 0.808511 (2390 2985);
WIRE 16 -1 (5300 800)(5100 800);
WIRE 16 -1 (5300 725)(5300 800);
WIRE 16 -1 (5500 725)(5500 800);
WIRE 16 -1 (5850 800)(5500 800);
FORCEPROP 2 LAST SIG_NAME P3V3_BMC_USB2AV33
J 0
(5165 810);
DISPLAY 0.808511 (5165 810);
WIRE 16 -1 (5500 800)(5300 800);
WIRE 16 -1 (5500 4375)(4900 4375);
FORCEPROP 2 LAST SIG_NAME V_DACB_R
J 0
(4965 4385);
DISPLAY 0.808511 (4965 4385);
WIRE 16 -1 (6000 1625)(5525 1625);
FORCEPROP 2 LAST SIG_NAME SYS_PWRBTN_N
J 2
(6040 1635);
DISPLAY 0.808511 (6040 1635);
WIRE 16 -1 (3000 1675)(2250 1675);
FORCEPROP 2 LAST SIG_NAME JTAG_SCM_TDO
J 0
(2515 1685);
DISPLAY 0.808511 (2515 1685);
WIRE 16 -1 (-625 2775)(450 2775);
FORCEPROP 2 LAST SIG_NAME PGPPA_BMC_AUX_SENSOR
J 0
(-560 2785);
DISPLAY 0.808511 (-560 2785);
WIRE 16 -1 (450 3575)(-725 3575);
FORCEPROP 2 LAST SIG_NAME FM_PCH_BEEP_LED
J 0
(-735 3585);
DISPLAY 0.851064 (-735 3585);
WIRE 2 -1 (-725 3625)(450 3625);
FORCEPROP 2 LAST SIG_NAME FM_P12V_HSC_ENABLE_R1
J 0
(-485 3635);
DISPLAY 0.808511 (-485 3635);
WIRE 16 -1 (450 3675)(-725 3675);
FORCEPROP 2 LAST SIG_NAME FM_HDD_LED_N
J 0
(-735 3685);
DISPLAY 0.851064 (-735 3685);
WIRE 16 -1 (-725 3725)(450 3725);
FORCEPROP 2 LAST SIG_NAME GPU_WP_HW_CTRL_R_N
J 0
(-735 3735);
DISPLAY 0.808511 (-735 3735);
WIRE 16 -1 (-725 3775)(450 3775);
FORCEPROP 2 LAST SIG_NAME GPU_NVS_PWR_BRAKE_R_N
J 0
(-735 3785);
DISPLAY 0.808511 (-735 3785);
WIRE 16 -1 (450 3875)(-725 3875);
FORCEPROP 2 LAST SIG_NAME IRQ_PCH_TPM_SPI_N
J 0
(-660 3885);
DISPLAY 0.851064 (-660 3885);
WIRE 16 -1 (450 3825)(-725 3825);
FORCEPROP 2 LAST SIG_NAME USB_OC0_REAR_R_N
J 0
(-660 3835);
DISPLAY 0.851064 (-660 3835);
WIRE 16 -1 (-2225 2625)(-1400 2625);
FORCEPROP 2 LAST SIG_NAME SMB_BMC_ALERT9_N
J 0
(-2185 2635);
DISPLAY 0.808511 (-2185 2635);
WIRE 16 -1 (-2225 2575)(-1400 2575);
FORCEPROP 2 LAST SIG_NAME SMB_BMC_ALERT10_N
J 0
(-2185 2585);
DISPLAY 0.808511 (-2185 2585);
WIRE 16 -1 (-2625 1300)(-2625 1250);
WIRE 16 -1 (-2625 1425)(-2625 1300);
WIRE 16 -1 (-2425 1300)(-2425 1250);
WIRE 16 -1 (-2125 1300)(-2425 1300);
WIRE 16 -1 (-2425 1300)(-2625 1300);
FORCEPROP 2 LAST SIG_NAME P3V3_SENSOR
J 0
(-2560 1310);
DISPLAY 0.808511 (-2560 1310);
WIRE 16 -1 (-2625 175)(-2625 125);
WIRE 16 -1 (-2625 300)(-2625 175);
WIRE 16 -1 (-2425 175)(-2425 125);
WIRE 16 -1 (-2125 175)(-2425 175);
WIRE 16 -1 (-2425 175)(-2625 175);
FORCEPROP 2 LAST SIG_NAME P2V5_SENSOR
J 0
(-2560 185);
DISPLAY 0.808511 (-2560 185);
WIRE 16 -1 (-2625 -800)(-2625 -925);
WIRE 16 -1 (-2625 -925)(-2625 -975);
WIRE 16 -1 (-2425 -925)(-2625 -925);
FORCEPROP 2 LAST SIG_NAME P1V8_SENSOR
J 0
(-2560 -915);
DISPLAY 0.808511 (-2560 -915);
WIRE 16 -1 (-2425 -925)(-2425 -975);
WIRE 16 -1 (-2125 -925)(-2425 -925);
WIRE 16 -1 (5025 -1150)(5600 -1150);
FORCEPROP 2 LAST SIG_NAME PECI_BMC
J 0
(5015 -1140);
DISPLAY 0.808511 (5015 -1140);
WIRE 16 -1 (5500 4275)(4900 4275);
FORCEPROP 2 LAST SIG_NAME V_DACG_R
J 0
(4965 4285);
DISPLAY 0.808511 (4965 4285);
WIRE 16 -1 (4000 750)(4000 825);
WIRE 16 -1 (4325 825)(4000 825);
WIRE 16 -1 (3800 825)(3600 825);
FORCEPROP 2 LAST SIG_NAME P1V8_BMC_USB2AV18
J 0
(3665 835);
DISPLAY 0.808511 (3665 835);
WIRE 16 -1 (4000 825)(3800 825);
WIRE 16 -1 (3800 750)(3800 825);
WIRE 16 -1 (4125 1675)(4925 1675);
FORCEPROP 2 LAST SIG_NAME SYS_BMC_PWRBTN_R_N
J 2
(4815 1685);
DISPLAY 0.808511 (4815 1685);
WIRE 16 3135 (4575 -1500)(4575 -925);
WIRE 16 3135 (4575 -1500)(6150 -1500);
WIRE 16 3135 (6150 -925)(4575 -925);
WIRE 16 3135 (6150 -925)(6150 -1500);
WIRE 16 -1 (1850 525)(2600 525);
FORCEPROP 2 LAST SIG_NAME BMC_CLK_25M
J 0
(2115 535);
DISPLAY 0.808511 (2115 535);
WIRE 16 -1 (250 -25)(650 -25);
FORCEPROP 2 LAST SIG_NAME P3V_BAT_R
J 0
(240 -15);
DISPLAY 0.808511 (240 -15);
WIRE 16 -1 (650 -25)(650 -75);
WIRE 16 -1 (-400 1975)(-1075 1975);
FORCEPROP 2 LAST SIG_NAME JTAG_1_BMC_TDO_R
J 0
(-1110 1985);
DISPLAY 0.808511 (-1110 1985);
WIRE 16 -1 (-625 2275)(450 2275);
FORCEPROP 2 LAST SIG_NAME SMB_BMC_ALERT16_N
J 0
(-585 2285);
DISPLAY 0.808511 (-585 2285);
WIRE 16 -1 (-625 2425)(450 2425);
FORCEPROP 2 LAST SIG_NAME BSM_PRSNT_R_N
J 0
(-585 2435);
DISPLAY 0.808511 (-585 2435);
WIRE 16 -1 (-625 2525)(450 2525);
FORCEPROP 2 LAST SIG_NAME P1V0_SENSOR
J 0
(-560 2535);
DISPLAY 0.808511 (-560 2535);
WIRE 16 -1 (450 2575)(-1200 2575);
FORCEPROP 2 LAST SIG_NAME SMB_BMC_ALERT10_R_N
J 0
(-560 2585);
DISPLAY 0.808511 (-560 2585);
WIRE 16 -1 (450 2625)(-1200 2625);
FORCEPROP 2 LAST SIG_NAME SMB_BMC_ALERT9_R_N
J 0
(-560 2635);
DISPLAY 0.808511 (-560 2635);
WIRE 16 -1 (-725 3375)(450 3375);
FORCEPROP 2 LAST SIG_NAME IRQ_OC_DETECT_EN_N
J 0
(-710 3385);
DISPLAY 0.808511 (-710 3385);
WIRE 16 -1 (-725 3425)(450 3425);
FORCEPROP 2 LAST SIG_NAME IRQ_UV_DETECT_N
J 0
(-710 3435);
DISPLAY 0.808511 (-710 3435);
WIRE 16 -1 (450 3475)(-725 3475);
FORCEPROP 2 LAST SIG_NAME IRQ_OC_DETECT_N
J 0
(-710 3485);
DISPLAY 0.808511 (-710 3485);
WIRE 2 -1 (-725 3525)(450 3525);
FORCEPROP 2 LAST SIG_NAME FM_SOL_UART_CH_SEL_R1
J 0
(-510 3535);
DISPLAY 0.851064 (-510 3535);
WIRE 16 -1 (-725 3175)(450 3175);
FORCEPROP 2 LAST SIG_NAME PWRGD_CPUPWRGD_LVC1
J 0
(-710 3185);
DISPLAY 0.808511 (-710 3185);
WIRE 16 -1 (-725 3225)(450 3225);
FORCEPROP 2 LAST SIG_NAME PWRGD_PCH_PWROK
J 0
(-710 3235);
DISPLAY 0.808511 (-710 3235);
WIRE 16 -1 (-725 3275)(450 3275);
FORCEPROP 2 LAST SIG_NAME IRQ_CPU1_VRHOT_N
J 0
(-710 3285);
DISPLAY 0.808511 (-710 3285);
WIRE 16 -1 (-625 2975)(450 2975);
FORCEPROP 2 LAST SIG_NAME P5V_SENSOR
J 0
(-560 2985);
DISPLAY 0.808511 (-560 2985);
WIRE 2 -1 (-1900 3525)(-925 3525);
FORCEPROP 2 LAST SIG_NAME FM_SOL_UART_CH_SEL
J 0
(-1860 3535);
DISPLAY 0.851064 (-1860 3535);
WIRE 2 -1 (-1900 3625)(-925 3625);
FORCEPROP 2 LAST SIG_NAME FM_P12V_HSC_ENABLE
J 0
(-1860 3635);
DISPLAY 0.808511 (-1860 3635);
WIRE 16 -1 (-2050 4075)(-2900 4075);
FORCEPROP 2 LAST SIG_NAME RST_EXTRST_N
J 0
(-2610 4085);
DISPLAY 0.808511 (-2610 4085);
WIRE 16 -1 (-2900 4175)(-2900 4075);
WIRE 16 -1 (-2650 4175)(-2650 4125);
WIRE 16 -1 (-2650 4125)(-2050 4125);
FORCEPROP 2 LAST SIG_NAME RST_BMC_SRST_N
J 0
(-2610 4135);
DISPLAY 0.808511 (-2610 4135);
WIRE 16 -1 (-625 2675)(450 2675);
FORCEPROP 2 LAST SIG_NAME P3V_BAT_SENSOR
J 0
(-560 2685);
DISPLAY 0.808511 (-560 2685);
WIRE 16 -1 (-625 2725)(450 2725);
FORCEPROP 2 LAST SIG_NAME P1V2_SENSOR
J 0
(-560 2735);
DISPLAY 0.808511 (-560 2735);
WIRE 16 -1 (2875 4125)(2250 4125);
FORCEPROP 2 LAST SIG_NAME V_VGAHS_R
J 0
(2390 4135);
DISPLAY 0.808511 (2390 4135);
WIRE 16 -1 (2250 4075)(2875 4075);
FORCEPROP 2 LAST SIG_NAME V_VGAVS_R
J 0
(2390 4085);
DISPLAY 0.808511 (2390 4085);
WIRE 16 -1 (3325 3575)(2250 3575);
FORCEPROP 2 LAST SIG_NAME FM_ADR_COMPLETE
J 0
(2440 3585);
DISPLAY 0.808511 (2440 3585);
WIRE 16 -1 (2250 3525)(3325 3525);
FORCEPROP 2 LAST SIG_NAME FM_SPD_REMOTE_EN_R
J 0
(2440 3535);
DISPLAY 0.808511 (2440 3535);
WIRE 16 -1 (2250 3175)(3425 3175);
FORCEPROP 2 LAST SIG_NAME H_CPU1_MEMTRIP_LVC1_N
J 0
(2415 3185);
DISPLAY 0.808511 (2415 3185);
WIRE 16 -1 (3100 3125)(2250 3125);
FORCEPROP 2 LAST SIG_NAME BMC_HEARTBEAT_N
J 0
(2415 3135);
DISPLAY 0.808511 (2415 3135);
WIRE 16 -1 (3200 2625)(2250 2625);
FORCEPROP 2 LAST SIG_NAME USB_HOST_BMC_B_R_DN
J 0
(2365 2635);
DISPLAY 0.808511 (2365 2635);
WIRE 16 -1 (3025 2325)(2250 2325);
FORCEPROP 2 LAST SIG_NAME PECI_BMC_R
J 0
(2440 2335);
DISPLAY 0.808511 (2440 2335);
WIRE 16 -1 (450 1775)(-525 1775);
FORCEPROP 2 LAST SIG_NAME JTAG_SCM_TCK
J 0
(-460 1785);
DISPLAY 0.808511 (-460 1785);
WIRE 16 -1 (450 1825)(-525 1825);
FORCEPROP 2 LAST SIG_NAME JTAG_SCM_NTRST
J 0
(-460 1835);
DISPLAY 0.808511 (-460 1835);
WIRE 16 -1 (-625 2325)(450 2325);
FORCEPROP 2 LAST SIG_NAME FM_PCHHOT_R_N
J 0
(-585 2335);
DISPLAY 0.808511 (-585 2335);
WIRE 16 -1 (-625 2375)(450 2375);
FORCEPROP 2 LAST SIG_NAME FM_BMC_EN_DET_R
J 0
(-585 2385);
DISPLAY 0.808511 (-585 2385);
WIRE 16 -1 (-625 2475)(450 2475);
FORCEPROP 2 LAST SIG_NAME SMB_BMC_ALERT12_N
J 0
(-585 2485);
DISPLAY 0.808511 (-585 2485);
WIRE 16 -1 (-625 2875)(450 2875);
FORCEPROP 2 LAST SIG_NAME P2V5_SENSOR
J 0
(-560 2885);
DISPLAY 0.808511 (-560 2885);
WIRE 16 -1 (-625 2925)(450 2925);
FORCEPROP 2 LAST SIG_NAME P3V3_SENSOR
J 0
(-560 2935);
DISPLAY 0.808511 (-560 2935);
WIRE 16 -1 (-625 3025)(450 3025);
FORCEPROP 2 LAST SIG_NAME P12V_SENSOR
J 0
(-560 3035);
DISPLAY 0.808511 (-560 3035);
WIRE 16 -1 (-725 3125)(450 3125);
FORCEPROP 2 LAST SIG_NAME FM_BIOS_POST_CMPLT_BMC_N
J 0
(-710 3135);
DISPLAY 0.808511 (-710 3135);
WIRE 16 -1 (450 4175)(-1025 4175);
FORCEPROP 2 LAST SIG_NAME FM_BMC_SSPRST_N
J 0
(-475 4185);
DISPLAY 0.808511 (-475 4185);
WIRE 16 -1 (-1025 4250)(-1025 4175);
WIRE 16 -1 (-300 4075)(300 4075);
FORCEPROP 2 LAST SIG_NAME RST_SPI_FLASH_N
J 0
(-310 4085);
DISPLAY 0.808511 (-310 4085);
WIRE 16 -1 (300 4075)(300 4025);
WIRE 16 -1 (300 4025)(450 4025);
WIRE 16 -1 (-625 4025)(300 4025);
WIRE 16 -1 (-1750 3975)(450 3975);
FORCEPROP 2 LAST SIG_NAME PD_SP_ENTEST
J 0
(-1460 3985);
DISPLAY 0.808511 (-1460 3985);
WIRE 16 -1 (-1450 4025)(-825 4025);
FORCEPROP 2 LAST SIG_NAME BMC_RSTIND_N
J 0
(-1460 4035);
DISPLAY 0.851064 (-1460 4035);
WIRE 16 -1 (450 3325)(-725 3325);
FORCEPROP 2 LAST SIG_NAME IRQ_CPU0_VRHOT_N
J 0
(-710 3335);
DISPLAY 0.808511 (-710 3335);
WIRE 16 -1 (3875 2325)(3225 2325);
FORCEPROP 2 LAST SIG_NAME PECI_BMC
J 0
(3365 2335);
DISPLAY 0.808511 (3365 2335);
WIRE 16 -1 (4525 4000)(5525 4000);
FORCEPROP 2 LAST SIG_NAME RST_BMC_RSTBTN_OUT_N
J 2
(5540 4010);
DISPLAY 0.808511 (5540 4010);
WIRE 16 -1 (5500 4175)(4900 4175);
FORCEPROP 2 LAST SIG_NAME V_DACR_R
J 0
(4965 4185);
DISPLAY 0.808511 (4965 4185);
WIRE 16 -1 (4525 3900)(5525 3900);
FORCEPROP 2 LAST SIG_NAME SYS_BMC_PWRBTN_R1_N
J 0
(4790 3910);
DISPLAY 0.851064 (4790 3910);
WIRE 2 -1 (5075 3725)(4125 3725);
FORCEPROP 2 LAST SIG_NAME FM_JTAG_BMC_MUX_SEL
J 0
(4290 3735);
DISPLAY 0.851064 (4290 3735);
WIRE 16 -1 (2250 1525)(3100 1525);
FORCEPROP 2 LAST SIG_NAME FM_INTRUDER_R_N
J 0
(2390 1535);
DISPLAY 0.808511 (2390 1535);
WIRE 16 -1 (3300 1925)(3300 1525);
WIRE 16 -1 (4075 1925)(3300 1925);
FORCEPROP 2 LAST SIG_NAME FM_INTRUDER_N
J 0
(3415 1935);
DISPLAY 0.808511 (3415 1935);
WIRE 16 -1 (4075 1975)(2250 1975);
FORCEPROP 2 LAST SIG_NAME JTAG_1_BMC_TDI_R
J 2
(4025 1985);
DISPLAY 0.808511 (4025 1985);
WIRE 16 -1 (4075 2025)(2250 2025);
FORCEPROP 2 LAST SIG_NAME JTAG_1_BMC_TMS_R
J 2
(4025 2035);
DISPLAY 0.808511 (4025 2035);
WIRE 16 -1 (4075 2075)(2250 2075);
FORCEPROP 2 LAST SIG_NAME JTAG_1_BMC_TCK_R
J 2
(4025 2085);
DISPLAY 0.808511 (4025 2085);
WIRE 16 -1 (4075 2125)(2250 2125);
FORCEPROP 2 LAST SIG_NAME JTAG_1_BMC_TRST_R
J 2
(4065 2135);
DISPLAY 0.808511 (4065 2135);
WIRE 16 -1 (4225 3425)(5150 3425);
FORCEPROP 2 LAST SIG_NAME SYS_BMC_PWRBTN_R_N
J 2
(5150 3435);
DISPLAY 0.808511 (5150 3435);
WIRE 16 -1 (5125 3550)(4200 3550);
FORCEPROP 2 LAST SIG_NAME PWR_BTN_BMC_N
J 2
(5140 3560);
DISPLAY 0.808511 (5140 3560);
WIRE 16 -1 (4225 3375)(5150 3375);
FORCEPROP 2 LAST SIG_NAME ID_RST_BTN_BMC_N
J 2
(5150 3385);
DISPLAY 0.808511 (5150 3385);
WIRE 16 -1 (4225 3275)(5150 3275);
FORCEPROP 2 LAST SIG_NAME PWR_LED
J 0
(4890 3285);
DISPLAY 0.808511 (4890 3285);
WIRE 16 -1 (4225 3325)(5150 3325);
FORCEPROP 2 LAST SIG_NAME RST_BMC_RSTBTN_OUT_N
J 2
(5150 3335);
DISPLAY 0.808511 (5150 3335);
WIRE 16 -1 (3400 2825)(3675 2825);
WIRE 16 -1 (3675 2825)(4450 2825);
FORCEPROP 2 LAST SIG_NAME USB_HOST_BMC_A_DP
J 2
(4450 2835);
DISPLAY 0.808511 (4450 2835);
WIRE 16 -1 (3675 3050)(3675 2825);
WIRE 16 -1 (3800 3050)(3675 3050);
WIRE 16 -1 (3725 2775)(3400 2775);
WIRE 16 -1 (4450 2775)(3725 2775);
FORCEPROP 2 LAST SIG_NAME USB_HOST_BMC_A_DN
J 2
(4450 2785);
DISPLAY 0.808511 (4450 2785);
WIRE 16 -1 (3725 2975)(3725 2775);
WIRE 16 -1 (3800 2975)(3725 2975);
WIRE 16 -1 (3400 2675)(4450 2675);
FORCEPROP 2 LAST SIG_NAME USB_HOST_BMC_B_DP
J 2
(4450 2685);
DISPLAY 0.808511 (4450 2685);
WIRE 16 -1 (4450 2625)(3400 2625);
FORCEPROP 2 LAST SIG_NAME USB_HOST_BMC_B_DN
J 2
(4450 2635);
DISPLAY 0.808511 (4450 2635);
WIRE 16 -1 (450 1675)(-525 1675);
FORCEPROP 2 LAST SIG_NAME JTAG_SCM_TDI
J 0
(-460 1685);
DISPLAY 0.808511 (-460 1685);
WIRE 16 -1 (2250 2575)(2250 2375);
WIRE 16 -1 (2250 2575)(4450 2575);
FORCEPROP 2 LAST SIG_NAME PVCCIO_PECI_BMC
J 2
(2940 2585);
DISPLAY 0.808511 (2940 2585);
WIRE 16 -1 (4450 2475)(4450 2575);
WIRE 16 -1 (4675 2575)(4450 2575);
WIRE 16 -1 (4825 2575)(4675 2575);
WIRE 16 -1 (4675 2475)(4675 2575);
WIRE 16 -1 (2250 2675)(3200 2675);
FORCEPROP 2 LAST SIG_NAME USB_HOST_BMC_B_R_DP
J 0
(2365 2685);
DISPLAY 0.808511 (2365 2685);
WIRE 16 -1 (2250 2775)(3200 2775);
FORCEPROP 2 LAST SIG_NAME USB_HOST_BMC_A_R_DN
J 0
(2365 2785);
DISPLAY 0.808511 (2365 2785);
WIRE 16 -1 (3200 2825)(2250 2825);
FORCEPROP 2 LAST SIG_NAME USB_HOST_BMC_A_R_DP
J 0
(2365 2835);
DISPLAY 0.808511 (2365 2835);
WIRE 16 -1 (3100 2925)(2250 2925);
FORCEPROP 2 LAST SIG_NAME P1V8_BMC_USB2AV18
J 0
(2390 2935);
DISPLAY 0.808511 (2390 2935);
WIRE 16 -1 (2250 3225)(3425 3225);
FORCEPROP 2 LAST SIG_NAME H_CPU0_MEMTRIP_LVC1_N
J 0
(2415 3235);
DISPLAY 0.808511 (2415 3235);
WIRE 16 -1 (4025 3275)(2250 3275);
FORCEPROP 2 LAST SIG_NAME BMC_PWR_LED
J 0
(2415 3285);
DISPLAY 0.808511 (2415 3285);
WIRE 16 -1 (4025 3325)(2250 3325);
FORCEPROP 2 LAST SIG_NAME RST_BMC_RSTBTN_OUT_R_N
J 0
(2415 3335);
DISPLAY 0.808511 (2415 3335);
WIRE 16 -1 (4025 3375)(2250 3375);
FORCEPROP 2 LAST SIG_NAME ID_RST_BTN_BMC_R_N
J 0
(2415 3385);
DISPLAY 0.808511 (2415 3385);
WIRE 16 -1 (2250 3425)(3725 3425);
FORCEPROP 2 LAST SIG_NAME SYS_BMC_PWRBTN_R1_N
J 0
(2415 3435);
DISPLAY 0.851064 (2415 3435);
WIRE 16 -1 (3725 3425)(4025 3425);
WIRE 16 -1 (3725 3650)(3725 3425);
WIRE 16 -1 (3775 3650)(3725 3650);
WIRE 16 -1 (4000 3550)(3800 3550);
WIRE 16 -1 (3800 3475)(2250 3475);
WIRE 16 -1 (3800 3550)(3800 3475);
FORCEPROP 2 LAST SIG_NAME FM_PWR_BTN
J 0
(4765 3485);
DISPLAY 0.808511 (4765 3485);
WIRE 16 -1 (5125 3475)(3800 3475);
WIRE 16 -1 (3325 3625)(2250 3625);
FORCEPROP 0 LAST SIG_NAME FM_TPM_PRSNT_0_N
J 0
(2440 3635);
DISPLAY 0.808511 (2440 3635);
WIRE 16 -1 (3325 3675)(2250 3675);
FORCEPROP 2 LAST SIG_NAME FM_ADR_TRIGGER_N
J 0
(2440 3685);
DISPLAY 0.808511 (2440 3685);
WIRE 2 -1 (3925 3725)(2250 3725);
FORCEPROP 2 LAST SIG_NAME FM_JTAG_BMC_MUX_SEL_R1
J 0
(2440 3735);
DISPLAY 0.851064 (2440 3735);
WIRE 16 -1 (3325 3775)(2250 3775);
FORCEPROP 2 LAST SIG_NAME FM_PCIE_M2_SSD0_PRSNT_N
J 0
(2440 3785);
DISPLAY 0.808511 (2440 3785);
WIRE 16 -1 (2250 4025)(3100 4025);
FORCEPROP 2 LAST SIG_NAME V_BMC_DDC_SCL
J 0
(2415 4035);
DISPLAY 0.808511 (2415 4035);
WIRE 16 -1 (3325 3875)(2250 3875);
FORCEPROP 2 LAST SIG_NAME FM_PMBUS_ALERT_EN
J 0
(2440 3885);
DISPLAY 0.808511 (2440 3885);
WIRE 16 -1 (2250 3975)(3100 3975);
FORCEPROP 2 LAST SIG_NAME V_BMC_DDC_SDA
J 0
(2415 3985);
DISPLAY 0.808511 (2415 3985);
WIRE 16 -1 (3075 4075)(3625 4075);
FORCEPROP 2 LAST SIG_NAME V_VGAVS
J 2
(3615 4085);
DISPLAY 0.808511 (3615 4085);
WIRE 16 -1 (3075 4125)(3625 4125);
FORCEPROP 2 LAST SIG_NAME V_VGAHS
J 2
(3615 4135);
DISPLAY 0.808511 (3615 4135);
WIRE 16 -1 (3625 4225)(3100 4225);
FORCEPROP 2 LAST SIG_NAME V_DACR
J 2
(3615 4235);
DISPLAY 0.808511 (3615 4235);
WIRE 16 -1 (3625 4325)(3100 4325);
FORCEPROP 2 LAST SIG_NAME V_DACB
J 2
(3615 4335);
DISPLAY 0.808511 (3615 4335);
WIRE 16 -1 (3625 4275)(3100 4275);
FORCEPROP 2 LAST SIG_NAME V_DACG
J 2
(3615 4285);
DISPLAY 0.808511 (3615 4285);
WIRE 16 -1 (2250 4325)(2750 4325);
FORCEPROP 2 LAST SIG_NAME V_DACB_R
J 0
(2415 4325);
DISPLAY 0.808511 (2415 4325);
WIRE 16 -1 (2900 4325)(2750 4325);
WIRE 16 -1 (2750 4325)(2750 4625);
WIRE 16 -1 (2750 4625)(3075 4625);
WIRE 16 3135 (2825 4200)(3125 4200);
WIRE 16 3135 (2825 4375)(2825 4200);
WIRE 16 3135 (3125 4375)(3125 4200);
WIRE 16 3135 (3125 4375)(2825 4375);
WIRE 16 -1 (2250 4225)(2800 4225);
FORCEPROP 2 LAST SIG_NAME V_DACR_R
J 0
(2415 4225);
DISPLAY 0.808511 (2415 4225);
WIRE 16 -1 (2900 4225)(2800 4225);
WIRE 16 -1 (2800 4225)(2800 4525);
WIRE 16 -1 (2800 4525)(3075 4525);
WIRE 16 -1 (2250 4275)(2775 4275);
FORCEPROP 2 LAST SIG_NAME V_DACG_R
J 0
(2415 4275);
DISPLAY 0.808511 (2415 4275);
WIRE 16 -1 (2775 4275)(2900 4275);
WIRE 16 -1 (2775 4275)(2775 4575);
WIRE 16 -1 (2775 4575)(3075 4575);
WIRE 16 -1 (-500 -750)(-1075 -750);
FORCEPROP 2 LAST SIG_NAME BATTERY_DETECT
J 0
(-1060 -740);
DISPLAY 0.808511 (-1060 -740);
DOT 1 (250 -750);
DOT 1 (2775 4275);
DOT 1 (2800 4225);
DOT 1 (2750 4325);
DOT 1 (5450 -350);
DOT 1 (3250 -900);
DOT 1 (3725 2775);
DOT 1 (3675 2825);
DOT 1 (4450 2575);
DOT 1 (650 -975);
DOT 1 (-1300 -1400);
DOT 1 (3725 1225);
DOT 1 (6200 1225);
DOT 1 (5175 2175);
DOT 1 (6100 4275);
DOT 1 (6100 4175);
DOT 1 (4225 4000);
DOT 1 (4675 2575);
DOT 1 (4625 2200);
DOT 1 (5500 800);
DOT 1 (5300 800);
DOT 1 (5375 450);
DOT 1 (4000 825);
DOT 1 (3800 825);
DOT 1 (3875 475);
DOT 1 (300 4025);
DOT 1 (5650 -350);
DOT 1 (5275 -350);
DOT 1 (5525 -700);
DOT 1 (3375 -550);
DOT 1 (3175 -550);
DOT 1 (3000 -550);
DOT 1 (1100 -975);
DOT 1 (-2900 4425);
DOT 1 (-175 1000);
DOT 1 (-1650 1175);
DOT 1 (-1625 75);
DOT 1 (-2425 3250);
DOT 1 (-2625 3250);
DOT 1 (-2425 2300);
DOT 1 (-2625 2925);
DOT 1 (-2625 2300);
DOT 1 (-2425 1300);
DOT 1 (-2625 1975);
DOT 1 (-2625 1300);
DOT 1 (-2425 175);
DOT 1 (-2625 975);
DOT 1 (-2625 175);
DOT 1 (-1500 -1400);
DOT 1 (-1500 -1725);
DOT 1 (-2425 -925);
DOT 1 (-2625 -150);
DOT 1 (-2625 -925);
DOT 1 (-2625 -1250);
DOT 1 (4200 2975);
DOT 1 (3800 3475);
DOT 1 (3725 3425);
DOT 1 (650 -1450);
FORCENOTE
DVT CHANGE
(5425 2350) 0;
DISPLAY LEFT (5425 2350);
DISPLAY 1.021277 (5425 2350);
PAINT WHITE (5425 2350);
FORCENOTE
USB2AV18
(3900 1000) 0;
DISPLAY LEFT (3900 1000);
DISPLAY 1.021277 (3900 1000);
PAINT WHITE (3900 1000);
FORCENOTE
SD1 I/O VOLTAGE SELECTION
(2275 -75) 0;
DISPLAY LEFT (2275 -75);
DISPLAY 1.021277 (2275 -75);
PAINT WHITE (2275 -75);
FORCENOTE
CHANGE TO 10OHM_20221221
(2700 4175) 0;
DISPLAY LEFT (2700 4175);
DISPLAY 0.638298 (2700 4175);
PAINT WHITE (2700 4175);
FORCENOTE
RST_SPI_FLASH_N FOR SPI FLASH RESET
(-2975 4600) 0;
DISPLAY LEFT (-2975 4600);
DISPLAY 1.021277 (-2975 4600);
PAINT WHITE (-2975 4600);
FORCENOTE
PECI
(4800 -1025) 0;
DISPLAY LEFT (4800 -1025);
DISPLAY 1.276596 (4800 -1025);
PAINT WHITE (4800 -1025);
FORCENOTE
SD2 I/O VOLTAGE SELECTION
(4525 125) 0;
DISPLAY LEFT (4525 125);
DISPLAY 1.021277 (4525 125);
PAINT WHITE (4525 125);
FORCENOTE
USB2AV33
(5400 975) 0;
DISPLAY LEFT (5400 975);
DISPLAY 1.021277 (5400 975);
PAINT WHITE (5400 975);
FORCENOTE
FOR BMC
(350 1100) 0;
DISPLAY LEFT (350 1100);
DISPLAY 2.000000 (350 1100);
PAINT WHITE (350 1100);
FORCENOTE
NEED ADD TEST POINT FOR ICT
(-450 1500) 0;
DISPLAY LEFT (-450 1500);
DISPLAY 0.638298 (-450 1500);
PAINT WHITE (-450 1500);
FORCENOTE
NOTE:
(-2975 4675) 0;
DISPLAY LEFT (-2975 4675);
DISPLAY 0.808511 (-2975 4675);
PAINT WHITE (-2975 4675);
FORCENOTE
NOTE
(-450 1575) 0;
DISPLAY LEFT (-450 1575);
DISPLAY 0.808511 (-450 1575);
PAINT WHITE (-450 1575);
FORCENOTE
FOR CPLD UPGRATED ON MB
(4825 2500) 0;
DISPLAY LEFT (4825 2500);
DISPLAY 0.638298 (4825 2500);
PAINT WHITE (4825 2500);
FORCENOTE
PLACE PHYSICALLY CLOSE TO AST2600 CHIP
(4275 4600) 0;
DISPLAY LEFT (4275 4600);
DISPLAY 1.021277 (4275 4600);
PAINT WHITE (4275 4600);
QUIT
